G04*
G04 #@! TF.GenerationSoftware,Altium Limited,Altium Designer,23.0.1 (38)*
G04*
G04 Layer_Color=32896*
%FSLAX44Y44*%
%MOMM*%
G71*
G04*
G04 #@! TF.SameCoordinates,9A23C038-B079-480F-8166-AFFB5740F5AE*
G04*
G04*
G04 #@! TF.FilePolarity,Positive*
G04*
G01*
G75*
G36*
X227281Y218636D02*
X228792D01*
Y218499D01*
X229341D01*
Y218362D01*
X229890D01*
Y218224D01*
X230302D01*
Y218087D01*
X230577D01*
Y217950D01*
X230989D01*
Y217812D01*
X231263D01*
Y217675D01*
X231538D01*
Y217538D01*
X231813D01*
Y217400D01*
X231950D01*
Y217263D01*
X232225D01*
Y217126D01*
X232362D01*
Y216989D01*
X232637D01*
Y216851D01*
X232774D01*
Y216714D01*
X232911D01*
Y216577D01*
X233049D01*
Y216439D01*
X233186D01*
Y216302D01*
X233323D01*
Y216165D01*
X233461D01*
Y216027D01*
X233598D01*
Y215890D01*
X233735D01*
Y215753D01*
X233873D01*
Y215615D01*
X234010D01*
Y215478D01*
X234147D01*
Y215341D01*
X234284D01*
Y215203D01*
X234422D01*
Y215066D01*
Y214929D01*
X234559D01*
Y214791D01*
X234696D01*
Y214654D01*
Y214517D01*
X234834D01*
Y214380D01*
X234971D01*
Y214242D01*
Y214105D01*
X235108D01*
Y213967D01*
Y213830D01*
X235246D01*
Y213693D01*
Y213556D01*
X235383D01*
Y213418D01*
Y213281D01*
X235520D01*
Y213144D01*
Y213006D01*
Y212869D01*
X235658D01*
Y212732D01*
Y212594D01*
X235795D01*
Y212457D01*
Y212320D01*
Y212182D01*
Y212045D01*
X235932D01*
Y211908D01*
Y211770D01*
Y211633D01*
Y211496D01*
X236070D01*
Y211359D01*
Y211221D01*
Y211084D01*
Y210947D01*
Y210809D01*
Y210672D01*
Y210535D01*
X236207D01*
Y210397D01*
Y210260D01*
Y210123D01*
Y209985D01*
Y209848D01*
Y209711D01*
Y209573D01*
Y209436D01*
Y209299D01*
Y209161D01*
Y209024D01*
Y208887D01*
Y208749D01*
X236070D01*
Y208612D01*
Y208475D01*
Y208337D01*
Y208200D01*
Y208063D01*
X235932D01*
Y207925D01*
Y207788D01*
Y207651D01*
Y207514D01*
Y207376D01*
X235795D01*
Y207239D01*
Y207102D01*
Y206964D01*
X235658D01*
Y206827D01*
Y206690D01*
Y206552D01*
X235520D01*
Y206415D01*
Y206278D01*
Y206140D01*
X235383D01*
Y206003D01*
Y205866D01*
X235246D01*
Y205728D01*
Y205591D01*
X235108D01*
Y205454D01*
Y205317D01*
X234971D01*
Y205179D01*
X234834D01*
Y205042D01*
Y204905D01*
X234696D01*
Y204767D01*
Y204630D01*
X234559D01*
Y204493D01*
X234422D01*
Y204355D01*
X234284D01*
Y204218D01*
Y204081D01*
X234147D01*
Y203943D01*
X234010D01*
Y203806D01*
X233873D01*
Y203669D01*
X233735D01*
Y203531D01*
X233598D01*
Y203394D01*
X233461D01*
Y203257D01*
X233323D01*
Y203119D01*
X233186D01*
Y202982D01*
X233049D01*
Y202845D01*
X232911D01*
Y202708D01*
X232774D01*
Y202570D01*
X232499D01*
Y202433D01*
X232362D01*
Y202295D01*
X232087D01*
Y202158D01*
X231950D01*
Y202021D01*
X231675D01*
Y201884D01*
X231401D01*
Y201746D01*
X231263D01*
Y201609D01*
X230851D01*
Y201472D01*
X230577D01*
Y201334D01*
X230165D01*
Y201197D01*
X229753D01*
Y201060D01*
X229341D01*
Y200922D01*
X228654D01*
Y200785D01*
X215335D01*
Y200922D01*
X214648D01*
Y201060D01*
X214099D01*
Y201197D01*
X213687D01*
Y201334D01*
X213275D01*
Y201472D01*
X213000D01*
Y201609D01*
X212726D01*
Y201746D01*
X212451D01*
Y201884D01*
X212176D01*
Y202021D01*
X211902D01*
Y202158D01*
X211764D01*
Y202295D01*
X211490D01*
Y202433D01*
X211352D01*
Y202570D01*
X211215D01*
Y202708D01*
X211078D01*
Y202845D01*
X210803D01*
Y202982D01*
X210666D01*
Y203119D01*
X210529D01*
Y203257D01*
X210391D01*
Y203394D01*
X210254D01*
Y203531D01*
X210117D01*
Y203669D01*
X209979D01*
Y203806D01*
X209842D01*
Y203943D01*
X209705D01*
Y204081D01*
Y204218D01*
X209567D01*
Y204355D01*
X209430D01*
Y204493D01*
X209293D01*
Y204630D01*
Y204767D01*
X209155D01*
Y204905D01*
X209018D01*
Y205042D01*
Y205179D01*
X208881D01*
Y205317D01*
Y205454D01*
X208743D01*
Y205591D01*
Y205728D01*
X208606D01*
Y205866D01*
Y206003D01*
X208469D01*
Y206140D01*
Y206278D01*
X208331D01*
Y206415D01*
Y206552D01*
Y206690D01*
X208194D01*
Y206827D01*
Y206964D01*
Y207102D01*
X208057D01*
Y207239D01*
Y207376D01*
Y207514D01*
X207919D01*
Y207651D01*
Y207788D01*
Y207925D01*
Y208063D01*
Y208200D01*
X207782D01*
Y208337D01*
Y208475D01*
Y208612D01*
Y208749D01*
Y208887D01*
Y209024D01*
Y209161D01*
Y209299D01*
Y209436D01*
X207645D01*
Y209573D01*
Y209711D01*
Y209848D01*
Y209985D01*
X207782D01*
Y210123D01*
Y210260D01*
Y210397D01*
Y210535D01*
Y210672D01*
Y210809D01*
Y210947D01*
Y211084D01*
Y211221D01*
Y211359D01*
X207919D01*
Y211496D01*
Y211633D01*
Y211770D01*
Y211908D01*
X208057D01*
Y212045D01*
Y212182D01*
Y212320D01*
Y212457D01*
X208194D01*
Y212594D01*
Y212732D01*
Y212869D01*
X208331D01*
Y213006D01*
Y213144D01*
X208469D01*
Y213281D01*
Y213418D01*
Y213556D01*
X208606D01*
Y213693D01*
Y213830D01*
X208743D01*
Y213967D01*
X208881D01*
Y214105D01*
Y214242D01*
X209018D01*
Y214380D01*
Y214517D01*
X209155D01*
Y214654D01*
X209293D01*
Y214791D01*
Y214929D01*
X209430D01*
Y215066D01*
X209567D01*
Y215203D01*
Y215341D01*
X209705D01*
Y215478D01*
X209842D01*
Y215615D01*
X209979D01*
Y215753D01*
X210117D01*
Y215890D01*
X210254D01*
Y216027D01*
X210391D01*
Y216165D01*
X210529D01*
Y216302D01*
X210666D01*
Y216439D01*
X210803D01*
Y216577D01*
X210940D01*
Y216714D01*
X211078D01*
Y216851D01*
X211352D01*
Y216989D01*
X211490D01*
Y217126D01*
X211764D01*
Y217263D01*
X211902D01*
Y217400D01*
X212176D01*
Y217538D01*
X212451D01*
Y217675D01*
X212588D01*
Y217812D01*
X213000D01*
Y217950D01*
X213275D01*
Y218087D01*
X213687D01*
Y218224D01*
X213961D01*
Y218362D01*
X214511D01*
Y218499D01*
X215197D01*
Y218636D01*
X216570D01*
Y218774D01*
X216708D01*
Y218636D01*
X216845D01*
Y218774D01*
X227281D01*
Y218636D01*
D02*
G37*
G36*
X431198D02*
X431335D01*
Y218499D01*
Y218362D01*
Y218224D01*
Y218087D01*
Y217950D01*
Y217812D01*
Y217675D01*
Y217538D01*
Y217400D01*
Y217263D01*
Y217126D01*
Y216989D01*
Y216851D01*
Y216714D01*
Y216577D01*
Y216439D01*
Y216302D01*
Y216165D01*
Y216027D01*
Y215890D01*
Y215753D01*
Y215615D01*
Y215478D01*
Y215341D01*
Y215203D01*
Y215066D01*
Y214929D01*
Y214791D01*
Y214654D01*
Y214517D01*
Y214380D01*
Y214242D01*
Y214105D01*
Y213967D01*
Y213830D01*
Y213693D01*
Y213556D01*
Y213418D01*
Y213281D01*
Y213144D01*
Y213006D01*
Y212869D01*
Y212732D01*
Y212594D01*
Y212457D01*
Y212320D01*
Y212182D01*
Y212045D01*
Y211908D01*
Y211770D01*
Y211633D01*
Y211496D01*
Y211359D01*
Y211221D01*
Y211084D01*
Y210947D01*
Y210809D01*
Y210672D01*
Y210535D01*
Y210397D01*
Y210260D01*
Y210123D01*
Y209985D01*
Y209848D01*
Y209711D01*
Y209573D01*
Y209436D01*
Y209299D01*
Y209161D01*
Y209024D01*
Y208887D01*
Y208749D01*
Y208612D01*
Y208475D01*
Y208337D01*
Y208200D01*
Y208063D01*
Y207925D01*
Y207788D01*
Y207651D01*
Y207514D01*
Y207376D01*
Y207239D01*
Y207102D01*
Y206964D01*
Y206827D01*
Y206690D01*
Y206552D01*
Y206415D01*
Y206278D01*
Y206140D01*
Y206003D01*
Y205866D01*
Y205728D01*
Y205591D01*
Y205454D01*
Y205317D01*
Y205179D01*
Y205042D01*
Y204905D01*
Y204767D01*
Y204630D01*
Y204493D01*
Y204355D01*
Y204218D01*
Y204081D01*
Y203943D01*
Y203806D01*
Y203669D01*
Y203531D01*
Y203394D01*
Y203257D01*
Y203119D01*
Y202982D01*
Y202845D01*
Y202708D01*
Y202570D01*
Y202433D01*
Y202295D01*
Y202158D01*
Y202021D01*
Y201884D01*
Y201746D01*
Y201609D01*
Y201472D01*
Y201334D01*
Y201197D01*
Y201060D01*
Y200922D01*
Y200785D01*
Y200648D01*
Y200510D01*
Y200373D01*
Y200236D01*
Y200098D01*
Y199961D01*
Y199824D01*
Y199687D01*
Y199549D01*
Y199412D01*
Y199275D01*
Y199137D01*
Y199000D01*
Y198863D01*
Y198725D01*
Y198588D01*
Y198451D01*
Y198313D01*
Y198176D01*
Y198039D01*
Y197901D01*
Y197764D01*
Y197627D01*
Y197489D01*
Y197352D01*
Y197215D01*
Y197078D01*
Y196940D01*
Y196803D01*
Y196665D01*
Y196528D01*
Y196391D01*
Y196254D01*
Y196116D01*
Y195979D01*
Y195842D01*
Y195704D01*
Y195567D01*
Y195430D01*
Y195292D01*
Y195155D01*
Y195018D01*
Y194880D01*
Y194743D01*
Y194606D01*
Y194468D01*
Y194331D01*
Y194194D01*
Y194056D01*
Y193919D01*
Y193782D01*
Y193645D01*
Y193507D01*
Y193370D01*
Y193233D01*
Y193095D01*
Y192958D01*
Y192821D01*
Y192683D01*
Y192546D01*
Y192409D01*
Y192271D01*
Y192134D01*
Y191997D01*
Y191859D01*
Y191722D01*
Y191585D01*
Y191447D01*
Y191310D01*
Y191173D01*
Y191035D01*
Y190898D01*
Y190761D01*
Y190623D01*
Y190486D01*
Y190349D01*
Y190212D01*
Y190074D01*
Y189937D01*
Y189800D01*
Y189662D01*
Y189525D01*
Y189388D01*
Y189250D01*
Y189113D01*
Y188976D01*
Y188838D01*
Y188701D01*
Y188564D01*
Y188426D01*
Y188289D01*
Y188152D01*
Y188015D01*
Y187877D01*
Y187740D01*
Y187603D01*
Y187465D01*
Y187328D01*
Y187191D01*
Y187053D01*
Y186916D01*
Y186779D01*
Y186641D01*
Y186504D01*
Y186367D01*
Y186229D01*
Y186092D01*
Y185955D01*
Y185817D01*
Y185680D01*
Y185543D01*
Y185406D01*
Y185268D01*
Y185131D01*
Y184993D01*
Y184856D01*
Y184719D01*
Y184582D01*
Y184444D01*
Y184307D01*
Y184170D01*
Y184032D01*
Y183895D01*
Y183758D01*
Y183620D01*
Y183483D01*
Y183346D01*
Y183208D01*
Y183071D01*
Y182934D01*
Y182796D01*
Y182659D01*
Y182522D01*
Y182384D01*
Y182247D01*
Y182110D01*
Y181973D01*
Y181835D01*
Y181698D01*
Y181561D01*
Y181423D01*
Y181286D01*
Y181149D01*
Y181011D01*
Y180874D01*
Y180737D01*
Y180599D01*
Y180462D01*
Y180325D01*
Y180187D01*
Y180050D01*
Y179913D01*
Y179776D01*
Y179638D01*
Y179501D01*
Y179363D01*
Y179226D01*
Y179089D01*
Y178952D01*
Y178814D01*
Y178677D01*
Y178540D01*
Y178402D01*
Y178265D01*
Y178128D01*
Y177990D01*
Y177853D01*
Y177716D01*
Y177578D01*
Y177441D01*
Y177304D01*
Y177166D01*
Y177029D01*
Y176892D01*
Y176754D01*
Y176617D01*
Y176480D01*
Y176343D01*
Y176205D01*
Y176068D01*
Y175931D01*
Y175793D01*
Y175656D01*
Y175519D01*
Y175381D01*
Y175244D01*
Y175107D01*
Y174969D01*
Y174832D01*
Y174695D01*
Y174557D01*
Y174420D01*
Y174283D01*
Y174145D01*
Y174008D01*
Y173871D01*
Y173734D01*
Y173596D01*
Y173459D01*
Y173321D01*
Y173184D01*
Y173047D01*
Y172910D01*
Y172772D01*
Y172635D01*
Y172498D01*
Y172360D01*
Y172223D01*
Y172086D01*
Y171948D01*
Y171811D01*
Y171674D01*
Y171536D01*
Y171399D01*
Y171262D01*
Y171124D01*
Y170987D01*
Y170850D01*
Y170713D01*
Y170575D01*
Y170438D01*
Y170301D01*
Y170163D01*
Y170026D01*
Y169889D01*
Y169751D01*
Y169614D01*
Y169477D01*
Y169339D01*
Y169202D01*
Y169065D01*
Y168927D01*
Y168790D01*
Y168653D01*
Y168515D01*
Y168378D01*
Y168241D01*
Y168104D01*
Y167966D01*
Y167829D01*
Y167691D01*
Y167554D01*
Y167417D01*
Y167280D01*
Y167142D01*
Y167005D01*
Y166868D01*
Y166730D01*
Y166593D01*
Y166456D01*
Y166318D01*
Y166181D01*
Y166044D01*
Y165906D01*
Y165769D01*
Y165632D01*
Y165494D01*
Y165357D01*
Y165220D01*
Y165082D01*
Y164945D01*
Y164808D01*
Y164671D01*
Y164533D01*
Y164396D01*
Y164259D01*
Y164121D01*
Y163984D01*
Y163847D01*
X418015D01*
Y163709D01*
Y163572D01*
Y163435D01*
Y163297D01*
Y163160D01*
Y163023D01*
Y162885D01*
Y162748D01*
Y162611D01*
Y162473D01*
Y162336D01*
Y162199D01*
Y162062D01*
Y161924D01*
Y161787D01*
Y161649D01*
Y161512D01*
Y161375D01*
Y161238D01*
Y161100D01*
Y160963D01*
Y160826D01*
Y160688D01*
Y160551D01*
Y160414D01*
Y160276D01*
Y160139D01*
Y160002D01*
Y159864D01*
Y159727D01*
Y159590D01*
Y159452D01*
Y159315D01*
Y159178D01*
Y159040D01*
Y158903D01*
Y158766D01*
Y158629D01*
Y158491D01*
Y158354D01*
Y158217D01*
Y158079D01*
Y157942D01*
Y157805D01*
Y157667D01*
Y157530D01*
Y157393D01*
Y157255D01*
Y157118D01*
Y156981D01*
Y156843D01*
Y156706D01*
Y156569D01*
Y156432D01*
Y156294D01*
Y156157D01*
Y156019D01*
Y155882D01*
Y155745D01*
Y155608D01*
Y155470D01*
Y155333D01*
Y155196D01*
Y155058D01*
Y154921D01*
Y154784D01*
Y154646D01*
Y154509D01*
Y154372D01*
Y154234D01*
Y154097D01*
Y153960D01*
Y153822D01*
Y153685D01*
Y153548D01*
Y153411D01*
Y153273D01*
Y153136D01*
Y152999D01*
Y152861D01*
Y152724D01*
Y152587D01*
Y152449D01*
Y152312D01*
Y152175D01*
Y152037D01*
Y151900D01*
Y151763D01*
Y151625D01*
Y151488D01*
Y151351D01*
Y151213D01*
Y151076D01*
Y150939D01*
Y150801D01*
Y150664D01*
Y150527D01*
Y150389D01*
Y150252D01*
Y150115D01*
Y149978D01*
Y149840D01*
Y149703D01*
Y149566D01*
Y149428D01*
Y149291D01*
Y149154D01*
Y149016D01*
Y148879D01*
Y148742D01*
X431198D01*
Y148604D01*
X431335D01*
Y148467D01*
Y148330D01*
Y148192D01*
Y148055D01*
Y147918D01*
Y147781D01*
Y147643D01*
Y147506D01*
Y147368D01*
Y147231D01*
Y147094D01*
Y146957D01*
Y146819D01*
Y146682D01*
Y146545D01*
Y146407D01*
Y146270D01*
Y146133D01*
Y145995D01*
Y145858D01*
Y145721D01*
Y145583D01*
Y145446D01*
Y145309D01*
X418015D01*
Y145171D01*
Y145034D01*
Y144897D01*
Y144760D01*
Y144622D01*
Y144485D01*
Y144347D01*
Y144210D01*
Y144073D01*
Y143936D01*
Y143798D01*
Y143661D01*
Y143524D01*
Y143386D01*
Y143249D01*
Y143112D01*
Y142974D01*
Y142837D01*
Y142700D01*
Y142562D01*
Y142425D01*
Y142288D01*
Y142150D01*
Y142013D01*
Y141876D01*
Y141739D01*
Y141601D01*
Y141464D01*
Y141327D01*
Y141189D01*
Y141052D01*
Y140915D01*
Y140777D01*
Y140640D01*
Y140503D01*
Y140365D01*
Y140228D01*
Y140091D01*
Y139953D01*
Y139816D01*
Y139679D01*
Y139541D01*
Y139404D01*
Y139267D01*
Y139129D01*
Y138992D01*
Y138855D01*
Y138717D01*
Y138580D01*
Y138443D01*
Y138306D01*
Y138168D01*
Y138031D01*
Y137894D01*
Y137756D01*
Y137619D01*
Y137482D01*
Y137344D01*
Y137207D01*
Y137070D01*
Y136932D01*
Y136795D01*
Y136658D01*
Y136520D01*
Y136383D01*
Y136246D01*
Y136109D01*
Y135971D01*
Y135834D01*
Y135696D01*
Y135559D01*
Y135422D01*
Y135285D01*
Y135147D01*
Y135010D01*
Y134873D01*
Y134735D01*
Y134598D01*
Y134461D01*
Y134323D01*
Y134186D01*
Y134049D01*
Y133911D01*
Y133774D01*
Y133637D01*
Y133499D01*
Y133362D01*
Y133225D01*
Y133088D01*
Y132950D01*
Y132813D01*
Y132676D01*
Y132538D01*
Y132401D01*
Y132264D01*
Y132126D01*
Y131989D01*
Y131852D01*
Y131714D01*
Y131577D01*
Y131440D01*
Y131302D01*
Y131165D01*
Y131028D01*
Y130890D01*
Y130753D01*
Y130616D01*
Y130478D01*
Y130341D01*
Y130204D01*
Y130066D01*
X431335D01*
Y129929D01*
Y129792D01*
Y129655D01*
Y129517D01*
Y129380D01*
Y129243D01*
Y129105D01*
Y128968D01*
Y128831D01*
Y128693D01*
Y128556D01*
Y128419D01*
Y128281D01*
Y128144D01*
Y128007D01*
Y127869D01*
Y127732D01*
Y127595D01*
Y127458D01*
Y127320D01*
Y127183D01*
Y127045D01*
Y126908D01*
Y126771D01*
X431198D01*
Y126634D01*
X418015D01*
Y126496D01*
Y126359D01*
Y126222D01*
Y126084D01*
Y125947D01*
Y125810D01*
Y125672D01*
Y125535D01*
Y125398D01*
Y125260D01*
Y125123D01*
Y124986D01*
Y124848D01*
Y124711D01*
Y124574D01*
Y124437D01*
Y124299D01*
Y124162D01*
Y124024D01*
Y123887D01*
Y123750D01*
Y123613D01*
Y123475D01*
Y123338D01*
Y123201D01*
Y123063D01*
Y122926D01*
Y122789D01*
Y122651D01*
Y122514D01*
Y122377D01*
Y122239D01*
Y122102D01*
Y121965D01*
Y121827D01*
Y121690D01*
Y121553D01*
Y121416D01*
Y121278D01*
Y121141D01*
Y121004D01*
Y120866D01*
Y120729D01*
Y120592D01*
Y120454D01*
Y120317D01*
Y120180D01*
Y120042D01*
Y119905D01*
Y119768D01*
Y119630D01*
Y119493D01*
Y119356D01*
Y119218D01*
Y119081D01*
Y118944D01*
Y118806D01*
Y118669D01*
Y118532D01*
Y118394D01*
Y118257D01*
Y118120D01*
Y117983D01*
Y117845D01*
Y117708D01*
Y117571D01*
Y117433D01*
Y117296D01*
Y117159D01*
Y117021D01*
Y116884D01*
Y116747D01*
Y116609D01*
Y116472D01*
Y116335D01*
Y116198D01*
Y116060D01*
Y115923D01*
Y115786D01*
Y115648D01*
Y115511D01*
Y115373D01*
Y115236D01*
Y115099D01*
Y114962D01*
Y114824D01*
Y114687D01*
Y114550D01*
Y114412D01*
Y114275D01*
Y114138D01*
Y114000D01*
Y113863D01*
Y113726D01*
Y113588D01*
Y113451D01*
Y113314D01*
Y113176D01*
Y113039D01*
Y112902D01*
Y112765D01*
Y112627D01*
Y112490D01*
Y112353D01*
Y112215D01*
Y112078D01*
Y111941D01*
Y111803D01*
Y111666D01*
Y111529D01*
X431335D01*
Y111391D01*
Y111254D01*
Y111117D01*
Y110979D01*
Y110842D01*
Y110705D01*
Y110567D01*
Y110430D01*
Y110293D01*
Y110155D01*
Y110018D01*
Y109881D01*
Y109743D01*
Y109606D01*
Y109469D01*
Y109332D01*
Y109194D01*
Y109057D01*
Y108920D01*
Y108782D01*
Y108645D01*
Y108508D01*
Y108370D01*
Y108233D01*
Y108096D01*
X418015D01*
Y107958D01*
Y107821D01*
Y107684D01*
Y107546D01*
Y107409D01*
Y107272D01*
Y107135D01*
Y106997D01*
Y106860D01*
Y106722D01*
Y106585D01*
Y106448D01*
Y106311D01*
Y106173D01*
Y106036D01*
Y105899D01*
Y105761D01*
Y105624D01*
Y105487D01*
Y105349D01*
Y105212D01*
Y105075D01*
Y104937D01*
Y104800D01*
Y104663D01*
Y104525D01*
Y104388D01*
Y104251D01*
Y104114D01*
Y103976D01*
Y103839D01*
Y103701D01*
Y103564D01*
Y103427D01*
Y103290D01*
Y103152D01*
Y103015D01*
Y102878D01*
Y102740D01*
Y102603D01*
Y102466D01*
Y102328D01*
Y102191D01*
Y102054D01*
Y101916D01*
Y101779D01*
Y101642D01*
Y101504D01*
Y101367D01*
Y101230D01*
Y101093D01*
Y100955D01*
Y100818D01*
Y100681D01*
Y100543D01*
Y100406D01*
Y100269D01*
Y100131D01*
Y99994D01*
Y99857D01*
Y99719D01*
Y99582D01*
Y99445D01*
Y99307D01*
Y99170D01*
Y99033D01*
Y98895D01*
Y98758D01*
Y98621D01*
Y98483D01*
Y98346D01*
Y98209D01*
Y98071D01*
Y97934D01*
Y97797D01*
Y97660D01*
Y97522D01*
Y97385D01*
Y97248D01*
Y97110D01*
Y96973D01*
Y96836D01*
Y96698D01*
Y96561D01*
Y96424D01*
Y96286D01*
Y96149D01*
Y96012D01*
Y95875D01*
Y95737D01*
Y95600D01*
Y95463D01*
Y95325D01*
Y95188D01*
Y95051D01*
Y94913D01*
Y94776D01*
Y94639D01*
Y94501D01*
Y94364D01*
Y94227D01*
Y94089D01*
Y93952D01*
Y93815D01*
Y93677D01*
Y93540D01*
Y93403D01*
Y93265D01*
Y93128D01*
Y92991D01*
X431335D01*
Y92853D01*
Y92716D01*
Y92579D01*
Y92442D01*
Y92304D01*
Y92167D01*
Y92030D01*
Y91892D01*
Y91755D01*
Y91618D01*
Y91480D01*
Y91343D01*
Y91206D01*
Y91068D01*
Y90931D01*
Y90794D01*
Y90656D01*
Y90519D01*
Y90382D01*
Y90244D01*
Y90107D01*
Y89970D01*
Y89832D01*
Y89695D01*
Y89558D01*
Y89420D01*
Y89283D01*
Y89146D01*
Y89009D01*
Y88871D01*
Y88734D01*
Y88597D01*
Y88459D01*
Y88322D01*
Y88185D01*
Y88047D01*
Y87910D01*
Y87773D01*
Y87635D01*
Y87498D01*
Y87361D01*
Y87223D01*
Y87086D01*
Y86949D01*
Y86812D01*
Y86674D01*
Y86537D01*
Y86399D01*
Y86262D01*
Y86125D01*
Y85988D01*
Y85850D01*
Y85713D01*
Y85576D01*
Y85438D01*
Y85301D01*
Y85164D01*
Y85026D01*
Y84889D01*
Y84752D01*
Y84614D01*
Y84477D01*
Y84340D01*
Y84202D01*
Y84065D01*
Y83928D01*
Y83791D01*
Y83653D01*
Y83516D01*
Y83379D01*
Y83241D01*
Y83104D01*
Y82967D01*
Y82829D01*
Y82692D01*
Y82555D01*
Y82417D01*
Y82280D01*
Y82143D01*
Y82005D01*
Y81868D01*
Y81731D01*
Y81593D01*
Y81456D01*
Y81319D01*
Y81181D01*
Y81044D01*
Y80907D01*
Y80770D01*
Y80632D01*
X410875D01*
Y80770D01*
Y80907D01*
Y81044D01*
Y81181D01*
Y81319D01*
Y81456D01*
Y81593D01*
Y81731D01*
Y81868D01*
Y82005D01*
Y82143D01*
Y82280D01*
Y82417D01*
Y82555D01*
Y82692D01*
Y82829D01*
Y82967D01*
Y83104D01*
Y83241D01*
Y83379D01*
Y83516D01*
Y83653D01*
Y83791D01*
Y83928D01*
Y84065D01*
Y84202D01*
Y84340D01*
Y84477D01*
Y84614D01*
Y84752D01*
Y84889D01*
Y85026D01*
Y85164D01*
Y85301D01*
Y85438D01*
Y85576D01*
Y85713D01*
Y85850D01*
Y85988D01*
Y86125D01*
Y86262D01*
Y86399D01*
Y86537D01*
Y86674D01*
Y86812D01*
Y86949D01*
Y87086D01*
Y87223D01*
Y87361D01*
Y87498D01*
Y87635D01*
Y87773D01*
Y87910D01*
Y88047D01*
Y88185D01*
Y88322D01*
Y88459D01*
Y88597D01*
Y88734D01*
Y88871D01*
Y89009D01*
Y89146D01*
Y89283D01*
Y89420D01*
Y89558D01*
Y89695D01*
Y89832D01*
Y89970D01*
Y90107D01*
Y90244D01*
Y90382D01*
Y90519D01*
Y90656D01*
Y90794D01*
Y90931D01*
Y91068D01*
Y91206D01*
Y91343D01*
Y91480D01*
Y91618D01*
Y91755D01*
Y91892D01*
Y92030D01*
Y92167D01*
Y92304D01*
Y92442D01*
Y92579D01*
X410737D01*
Y92716D01*
Y92853D01*
X410600D01*
Y92991D01*
X410463D01*
Y93128D01*
X410325D01*
Y93265D01*
X410051D01*
Y93403D01*
X388767D01*
Y93265D01*
X388492D01*
Y93128D01*
X388217D01*
Y92991D01*
X388080D01*
Y92853D01*
Y92716D01*
X387943D01*
Y92579D01*
Y92442D01*
Y92304D01*
Y92167D01*
Y92030D01*
Y91892D01*
X387805D01*
Y91755D01*
X387943D01*
Y91618D01*
X387805D01*
Y91480D01*
Y91343D01*
X387943D01*
Y91206D01*
Y91068D01*
Y90931D01*
Y90794D01*
Y90656D01*
Y90519D01*
Y90382D01*
Y90244D01*
Y90107D01*
Y89970D01*
Y89832D01*
Y89695D01*
Y89558D01*
Y89420D01*
Y89283D01*
Y89146D01*
Y89009D01*
Y88871D01*
Y88734D01*
Y88597D01*
Y88459D01*
Y88322D01*
Y88185D01*
Y88047D01*
Y87910D01*
Y87773D01*
Y87635D01*
Y87498D01*
Y87361D01*
Y87223D01*
Y87086D01*
Y86949D01*
Y86812D01*
Y86674D01*
Y86537D01*
Y86399D01*
Y86262D01*
Y86125D01*
Y85988D01*
Y85850D01*
Y85713D01*
Y85576D01*
Y85438D01*
Y85301D01*
Y85164D01*
Y85026D01*
Y84889D01*
Y84752D01*
Y84614D01*
Y84477D01*
Y84340D01*
X387805D01*
Y84202D01*
Y84065D01*
Y83928D01*
X387668D01*
Y83791D01*
X387531D01*
Y83653D01*
X387393D01*
Y83516D01*
X387256D01*
Y83379D01*
X386844D01*
Y83241D01*
X378605D01*
Y83379D01*
X378193D01*
Y83516D01*
X378056D01*
Y83653D01*
X377919D01*
Y83791D01*
X377781D01*
Y83928D01*
X377644D01*
Y84065D01*
Y84202D01*
Y84340D01*
Y84477D01*
X377507D01*
Y84614D01*
Y84752D01*
Y84889D01*
Y85026D01*
Y85164D01*
Y85301D01*
Y85438D01*
Y85576D01*
Y85713D01*
Y85850D01*
Y85988D01*
Y86125D01*
Y86262D01*
Y86399D01*
Y86537D01*
Y86674D01*
Y86812D01*
Y86949D01*
Y87086D01*
Y87223D01*
Y87361D01*
Y87498D01*
Y87635D01*
Y87773D01*
Y87910D01*
Y88047D01*
Y88185D01*
Y88322D01*
Y88459D01*
Y88597D01*
Y88734D01*
Y88871D01*
Y89009D01*
Y89146D01*
Y89283D01*
Y89420D01*
Y89558D01*
Y89695D01*
Y89832D01*
Y89970D01*
Y90107D01*
Y90244D01*
Y90382D01*
X377644D01*
Y90519D01*
X377507D01*
Y90656D01*
Y90794D01*
X377644D01*
Y90931D01*
X377507D01*
Y91068D01*
Y91206D01*
Y91343D01*
Y91480D01*
Y91618D01*
Y91755D01*
X377369D01*
Y91892D01*
Y92030D01*
X377232D01*
Y92167D01*
Y92304D01*
X377095D01*
Y92442D01*
X376957D01*
Y92579D01*
X376820D01*
Y92716D01*
X376683D01*
Y92853D01*
X376545D01*
Y92991D01*
X376271D01*
Y93128D01*
X375996D01*
Y93265D01*
X375584D01*
Y93403D01*
X374486D01*
Y93265D01*
X374074D01*
Y93128D01*
X373799D01*
Y92991D01*
X373524D01*
Y92853D01*
X373387D01*
Y92716D01*
X373250D01*
Y92579D01*
X373112D01*
Y92442D01*
X372975D01*
Y92304D01*
Y92167D01*
X372838D01*
Y92030D01*
Y91892D01*
X372700D01*
Y91755D01*
Y91618D01*
X372563D01*
Y91480D01*
Y91343D01*
Y91206D01*
Y91068D01*
Y90931D01*
Y90794D01*
Y90656D01*
Y90519D01*
Y90382D01*
X372426D01*
Y90244D01*
X372563D01*
Y90107D01*
Y89970D01*
Y89832D01*
Y89695D01*
Y89558D01*
Y89420D01*
Y89283D01*
Y89146D01*
Y89009D01*
Y88871D01*
Y88734D01*
Y88597D01*
Y88459D01*
Y88322D01*
Y88185D01*
Y88047D01*
Y87910D01*
Y87773D01*
Y87635D01*
Y87498D01*
Y87361D01*
Y87223D01*
Y87086D01*
Y86949D01*
Y86812D01*
Y86674D01*
Y86537D01*
Y86399D01*
Y86262D01*
Y86125D01*
Y85988D01*
Y85850D01*
Y85713D01*
Y85576D01*
Y85438D01*
Y85301D01*
Y85164D01*
Y85026D01*
Y84889D01*
Y84752D01*
Y84614D01*
Y84477D01*
Y84340D01*
Y84202D01*
Y84065D01*
Y83928D01*
Y83791D01*
Y83653D01*
Y83516D01*
Y83379D01*
Y83241D01*
Y83104D01*
Y82967D01*
Y82829D01*
Y82692D01*
Y82555D01*
Y82417D01*
Y82280D01*
Y82143D01*
Y82005D01*
Y81868D01*
Y81731D01*
Y81593D01*
Y81456D01*
Y81319D01*
Y81181D01*
Y81044D01*
Y80907D01*
Y80770D01*
Y80632D01*
Y80495D01*
Y80358D01*
Y80220D01*
Y80083D01*
Y79946D01*
Y79808D01*
Y79671D01*
Y79534D01*
Y79396D01*
Y79259D01*
Y79122D01*
X372426D01*
Y78984D01*
Y78847D01*
Y78710D01*
X372289D01*
Y78573D01*
Y78435D01*
X372151D01*
Y78298D01*
X371876D01*
Y78161D01*
X371602D01*
Y78023D01*
X358145D01*
Y78161D01*
X357733D01*
Y78298D01*
X357595D01*
Y78435D01*
X357458D01*
Y78573D01*
X357321D01*
Y78710D01*
X357184D01*
Y78847D01*
Y78984D01*
Y79122D01*
Y79259D01*
Y79396D01*
Y79534D01*
Y79671D01*
Y79808D01*
Y79946D01*
Y80083D01*
Y80220D01*
Y80358D01*
Y80495D01*
Y80632D01*
Y80770D01*
Y80907D01*
Y81044D01*
Y81181D01*
Y81319D01*
Y81456D01*
Y81593D01*
Y81731D01*
Y81868D01*
Y82005D01*
Y82143D01*
Y82280D01*
Y82417D01*
Y82555D01*
Y82692D01*
Y82829D01*
Y82967D01*
Y83104D01*
Y83241D01*
Y83379D01*
Y83516D01*
Y83653D01*
Y83791D01*
Y83928D01*
Y84065D01*
Y84202D01*
Y84340D01*
Y84477D01*
Y84614D01*
Y84752D01*
Y84889D01*
Y85026D01*
Y85164D01*
Y85301D01*
Y85438D01*
Y85576D01*
Y85713D01*
Y85850D01*
Y85988D01*
Y86125D01*
Y86262D01*
Y86399D01*
Y86537D01*
Y86674D01*
Y86812D01*
Y86949D01*
Y87086D01*
X357046D01*
Y87223D01*
Y87361D01*
Y87498D01*
Y87635D01*
X356909D01*
Y87773D01*
X356772D01*
Y87910D01*
X356634D01*
Y88047D01*
X356497D01*
Y88185D01*
X356085D01*
Y88322D01*
X355673D01*
Y88185D01*
X355261D01*
Y88047D01*
X354986D01*
Y87910D01*
X354849D01*
Y87773D01*
Y87635D01*
X354712D01*
Y87498D01*
Y87361D01*
Y87223D01*
X354575D01*
Y87086D01*
Y86949D01*
Y86812D01*
Y86674D01*
Y86537D01*
Y86399D01*
Y86262D01*
Y86125D01*
Y85988D01*
Y85850D01*
Y85713D01*
Y85576D01*
Y85438D01*
Y85301D01*
Y85164D01*
Y85026D01*
Y84889D01*
Y84752D01*
Y84614D01*
Y84477D01*
Y84340D01*
Y84202D01*
Y84065D01*
Y83928D01*
Y83791D01*
Y83653D01*
Y83516D01*
Y83379D01*
Y83241D01*
Y83104D01*
Y82967D01*
Y82829D01*
Y82692D01*
Y82555D01*
Y82417D01*
Y82280D01*
Y82143D01*
Y82005D01*
Y81868D01*
Y81731D01*
Y81593D01*
Y81456D01*
Y81319D01*
Y81181D01*
Y81044D01*
Y80907D01*
Y80770D01*
Y80632D01*
Y80495D01*
Y80358D01*
Y80220D01*
Y80083D01*
Y79946D01*
Y79808D01*
Y79671D01*
Y79534D01*
Y79396D01*
Y79259D01*
Y79122D01*
Y78984D01*
Y78847D01*
X354437D01*
Y78710D01*
Y78573D01*
X354300D01*
Y78435D01*
X354163D01*
Y78298D01*
X354025D01*
Y78161D01*
X353613D01*
Y78023D01*
X327386D01*
Y78161D01*
X327111D01*
Y78298D01*
X326836D01*
Y78435D01*
X326699D01*
Y78573D01*
Y78710D01*
X326562D01*
Y78847D01*
Y78984D01*
X326424D01*
Y79122D01*
Y79259D01*
Y79396D01*
Y79534D01*
Y79671D01*
Y79808D01*
Y79946D01*
Y80083D01*
Y80220D01*
Y80358D01*
Y80495D01*
Y80632D01*
Y80770D01*
Y80907D01*
Y81044D01*
Y81181D01*
Y81319D01*
Y81456D01*
Y81593D01*
Y81731D01*
Y81868D01*
Y82005D01*
Y82143D01*
Y82280D01*
Y82417D01*
Y82555D01*
Y82692D01*
Y82829D01*
Y82967D01*
Y83104D01*
Y83241D01*
Y83379D01*
Y83516D01*
Y83653D01*
Y83791D01*
Y83928D01*
Y84065D01*
Y84202D01*
Y84340D01*
Y84477D01*
Y84614D01*
Y84752D01*
Y84889D01*
Y85026D01*
Y85164D01*
Y85301D01*
Y85438D01*
Y85576D01*
Y85713D01*
Y85850D01*
Y85988D01*
Y86125D01*
Y86262D01*
Y86399D01*
Y86537D01*
Y86674D01*
Y86812D01*
Y86949D01*
Y87086D01*
Y87223D01*
Y87361D01*
Y87498D01*
Y87635D01*
Y87773D01*
Y87910D01*
Y88047D01*
Y88185D01*
Y88322D01*
Y88459D01*
Y88597D01*
Y88734D01*
Y88871D01*
Y89009D01*
Y89146D01*
Y89283D01*
Y89420D01*
Y89558D01*
Y89695D01*
Y89832D01*
Y89970D01*
Y90107D01*
Y90244D01*
Y90382D01*
Y90519D01*
Y90656D01*
Y90794D01*
Y90931D01*
Y91068D01*
Y91206D01*
Y91343D01*
Y91480D01*
Y91618D01*
Y91755D01*
Y91892D01*
Y92030D01*
Y92167D01*
Y92304D01*
Y92442D01*
Y92579D01*
X326287D01*
Y92716D01*
Y92853D01*
X326150D01*
Y92991D01*
X326012D01*
Y93128D01*
X325875D01*
Y93265D01*
X325601D01*
Y93403D01*
X226732D01*
Y93540D01*
X226183D01*
Y93677D01*
X225771D01*
Y93815D01*
X225496D01*
Y93952D01*
X225221D01*
Y94089D01*
X224947D01*
Y94227D01*
X224672D01*
Y94364D01*
X224535D01*
Y94501D01*
X224260D01*
Y94639D01*
X224123D01*
Y94776D01*
X223986D01*
Y94913D01*
X223711D01*
Y95051D01*
X223574D01*
Y95188D01*
X223436D01*
Y95325D01*
X223299D01*
Y95463D01*
X223162D01*
Y95600D01*
X223024D01*
Y95737D01*
X222887D01*
Y95875D01*
X222750D01*
Y96012D01*
X222612D01*
Y96149D01*
X222475D01*
Y96286D01*
X222338D01*
Y96424D01*
Y96561D01*
X222201D01*
Y96698D01*
X222063D01*
Y96836D01*
X221926D01*
Y96973D01*
Y97110D01*
X221789D01*
Y97248D01*
X221651D01*
Y97385D01*
Y97522D01*
X221514D01*
Y97660D01*
X221377D01*
Y97797D01*
Y97934D01*
X221239D01*
Y98071D01*
Y98209D01*
X221102D01*
Y98346D01*
Y98483D01*
X220965D01*
Y98621D01*
Y98758D01*
Y98895D01*
X220827D01*
Y99033D01*
Y99170D01*
Y99307D01*
X220690D01*
Y99445D01*
Y99582D01*
Y99719D01*
X220553D01*
Y99857D01*
Y99994D01*
Y100131D01*
X220415D01*
Y100269D01*
Y100406D01*
Y100543D01*
Y100681D01*
Y100818D01*
X220278D01*
Y100955D01*
Y101093D01*
Y101230D01*
Y101367D01*
Y101504D01*
Y101642D01*
Y101779D01*
Y101916D01*
Y102054D01*
Y102191D01*
X220141D01*
Y102328D01*
Y102466D01*
X220278D01*
Y102603D01*
Y102740D01*
Y102878D01*
Y103015D01*
Y103152D01*
Y103290D01*
Y103427D01*
Y103564D01*
Y103701D01*
X220415D01*
Y103839D01*
Y103976D01*
Y104114D01*
Y104251D01*
Y104388D01*
Y104525D01*
X220553D01*
Y104663D01*
Y104800D01*
Y104937D01*
X220690D01*
Y105075D01*
Y105212D01*
Y105349D01*
X220827D01*
Y105487D01*
Y105624D01*
Y105761D01*
X220965D01*
Y105899D01*
Y106036D01*
X221102D01*
Y106173D01*
Y106311D01*
X221239D01*
Y106448D01*
Y106585D01*
X221377D01*
Y106722D01*
Y106860D01*
X221514D01*
Y106997D01*
X221651D01*
Y107135D01*
Y107272D01*
X221789D01*
Y107409D01*
X221926D01*
Y107546D01*
Y107684D01*
X222063D01*
Y107821D01*
X222201D01*
Y107958D01*
X222338D01*
Y108096D01*
X222475D01*
Y108233D01*
Y108370D01*
X222612D01*
Y108508D01*
X222750D01*
Y108645D01*
X222887D01*
Y108782D01*
X223024D01*
Y108920D01*
X223162D01*
Y109057D01*
X223436D01*
Y109194D01*
X223574D01*
Y109332D01*
X223711D01*
Y109469D01*
X223848D01*
Y109606D01*
X224123D01*
Y109743D01*
X224260D01*
Y109881D01*
X224535D01*
Y110018D01*
X224809D01*
Y110155D01*
X224947D01*
Y110293D01*
X225221D01*
Y110430D01*
X225496D01*
Y110567D01*
X225908D01*
Y110705D01*
X226320D01*
Y110842D01*
X226732D01*
Y110979D01*
X227144D01*
Y111117D01*
X227831D01*
Y111254D01*
X256255D01*
Y111391D01*
X257491D01*
Y111529D01*
X258178D01*
Y111666D01*
X258727D01*
Y111803D01*
X259002D01*
Y111941D01*
X259414D01*
Y112078D01*
X259688D01*
Y112215D01*
X259963D01*
Y112353D01*
X260237D01*
Y112490D01*
X260512D01*
Y112627D01*
X260787D01*
Y112765D01*
X260924D01*
Y112902D01*
X261199D01*
Y113039D01*
X261336D01*
Y113176D01*
X261473D01*
Y113314D01*
X261748D01*
Y113451D01*
X261885D01*
Y113588D01*
X262022D01*
Y113726D01*
X262160D01*
Y113863D01*
X262297D01*
Y114000D01*
X262435D01*
Y114138D01*
X262572D01*
Y114275D01*
X262709D01*
Y114412D01*
X262846D01*
Y114550D01*
X262984D01*
Y114687D01*
Y114824D01*
X263121D01*
Y114962D01*
X263258D01*
Y115099D01*
X263396D01*
Y115236D01*
Y115373D01*
X263533D01*
Y115511D01*
X263670D01*
Y115648D01*
Y115786D01*
X263808D01*
Y115923D01*
Y116060D01*
X263945D01*
Y116198D01*
Y116335D01*
X264082D01*
Y116472D01*
Y116609D01*
X264220D01*
Y116747D01*
Y116884D01*
X264357D01*
Y117021D01*
Y117159D01*
Y117296D01*
X264494D01*
Y117433D01*
Y117571D01*
Y117708D01*
X264632D01*
Y117845D01*
Y117983D01*
Y118120D01*
X264769D01*
Y118257D01*
Y118394D01*
Y118532D01*
Y118669D01*
Y118806D01*
X264906D01*
Y118944D01*
Y119081D01*
Y119218D01*
Y119356D01*
Y119493D01*
Y119630D01*
Y119768D01*
Y119905D01*
Y120042D01*
Y120180D01*
Y120317D01*
Y120454D01*
Y120592D01*
Y120729D01*
Y120866D01*
Y121004D01*
Y121141D01*
Y121278D01*
Y121416D01*
Y121553D01*
Y121690D01*
X264769D01*
Y121827D01*
Y121965D01*
Y122102D01*
Y122239D01*
Y122377D01*
X264632D01*
Y122514D01*
Y122651D01*
Y122789D01*
X264494D01*
Y122926D01*
Y123063D01*
Y123201D01*
X264357D01*
Y123338D01*
Y123475D01*
Y123613D01*
X264220D01*
Y123750D01*
Y123887D01*
X264082D01*
Y124024D01*
Y124162D01*
X263945D01*
Y124299D01*
Y124437D01*
X263808D01*
Y124574D01*
Y124711D01*
X263670D01*
Y124848D01*
X263533D01*
Y124986D01*
Y125123D01*
X263396D01*
Y125260D01*
X263258D01*
Y125398D01*
Y125535D01*
X263121D01*
Y125672D01*
X262984D01*
Y125810D01*
X262846D01*
Y125947D01*
X262709D01*
Y126084D01*
Y126222D01*
X262572D01*
Y126359D01*
X262435D01*
Y126496D01*
X262297D01*
Y126634D01*
X262160D01*
Y126771D01*
X262022D01*
Y126908D01*
X261748D01*
Y127045D01*
X261611D01*
Y127183D01*
X261473D01*
Y127320D01*
X261336D01*
Y127458D01*
X261061D01*
Y127595D01*
X260924D01*
Y127732D01*
X260649D01*
Y127869D01*
X260375D01*
Y128007D01*
X260237D01*
Y128144D01*
X259963D01*
Y128281D01*
X259688D01*
Y128419D01*
X259276D01*
Y128556D01*
X259002D01*
Y128693D01*
X258590D01*
Y128831D01*
X258040D01*
Y128968D01*
X257354D01*
Y129105D01*
X255981D01*
Y129243D01*
X255843D01*
Y129105D01*
X214648D01*
Y129243D01*
X214511D01*
Y129105D01*
X214236D01*
Y129243D01*
X213275D01*
Y129380D01*
X212588D01*
Y129517D01*
X212176D01*
Y129655D01*
X211764D01*
Y129792D01*
X211352D01*
Y129929D01*
X211078D01*
Y130066D01*
X210803D01*
Y130204D01*
X210529D01*
Y130341D01*
X210254D01*
Y130478D01*
X210117D01*
Y130616D01*
X209842D01*
Y130753D01*
X209705D01*
Y130890D01*
X209430D01*
Y131028D01*
X209293D01*
Y131165D01*
X209155D01*
Y131302D01*
X208881D01*
Y131440D01*
X208743D01*
Y131577D01*
X208606D01*
Y131714D01*
X208469D01*
Y131852D01*
X208331D01*
Y131989D01*
X208194D01*
Y132126D01*
X208057D01*
Y132264D01*
X207919D01*
Y132401D01*
Y132538D01*
X207782D01*
Y132676D01*
X207645D01*
Y132813D01*
X207507D01*
Y132950D01*
X207370D01*
Y133088D01*
Y133225D01*
X207233D01*
Y133362D01*
X207096D01*
Y133499D01*
Y133637D01*
X206958D01*
Y133774D01*
Y133911D01*
X206821D01*
Y134049D01*
Y134186D01*
X206684D01*
Y134323D01*
Y134461D01*
X206546D01*
Y134598D01*
Y134735D01*
X206409D01*
Y134873D01*
Y135010D01*
Y135147D01*
X206272D01*
Y135285D01*
Y135422D01*
Y135559D01*
X206134D01*
Y135696D01*
Y135834D01*
Y135971D01*
X205997D01*
Y136109D01*
Y136246D01*
Y136383D01*
Y136520D01*
Y136658D01*
X205860D01*
Y136795D01*
Y136932D01*
Y137070D01*
Y137207D01*
Y137344D01*
Y137482D01*
Y137619D01*
Y137756D01*
Y137894D01*
Y138031D01*
Y138168D01*
Y138306D01*
Y138443D01*
Y138580D01*
Y138717D01*
Y138855D01*
Y138992D01*
Y139129D01*
Y139267D01*
Y139404D01*
Y139541D01*
X205997D01*
Y139679D01*
Y139816D01*
Y139953D01*
Y140091D01*
Y140228D01*
X206134D01*
Y140365D01*
Y140503D01*
Y140640D01*
Y140777D01*
X206272D01*
Y140915D01*
Y141052D01*
Y141189D01*
X206409D01*
Y141327D01*
Y141464D01*
X206546D01*
Y141601D01*
Y141739D01*
Y141876D01*
X206684D01*
Y142013D01*
Y142150D01*
X206821D01*
Y142288D01*
Y142425D01*
X206958D01*
Y142562D01*
X207096D01*
Y142700D01*
Y142837D01*
X207233D01*
Y142974D01*
Y143112D01*
X207370D01*
Y143249D01*
X207507D01*
Y143386D01*
X207645D01*
Y143524D01*
Y143661D01*
X207782D01*
Y143798D01*
X207919D01*
Y143936D01*
X208057D01*
Y144073D01*
X208194D01*
Y144210D01*
X208331D01*
Y144347D01*
X208469D01*
Y144485D01*
X208606D01*
Y144622D01*
X208743D01*
Y144760D01*
X208881D01*
Y144897D01*
X209018D01*
Y145034D01*
X209155D01*
Y145171D01*
X209430D01*
Y145309D01*
X209567D01*
Y145446D01*
X209705D01*
Y145583D01*
X209979D01*
Y145721D01*
X210117D01*
Y145858D01*
X210391D01*
Y145995D01*
X210666D01*
Y146133D01*
X210940D01*
Y146270D01*
X211215D01*
Y146407D01*
X211627D01*
Y146545D01*
X212039D01*
Y146682D01*
X212451D01*
Y146819D01*
X213000D01*
Y146957D01*
X213687D01*
Y147094D01*
X240052D01*
Y147231D01*
X241013D01*
Y147368D01*
X241562D01*
Y147506D01*
X241974D01*
Y147643D01*
X242386D01*
Y147781D01*
X242661D01*
Y147918D01*
X243073D01*
Y148055D01*
X243347D01*
Y148192D01*
X243485D01*
Y148330D01*
X243759D01*
Y148467D01*
X244034D01*
Y148604D01*
X244171D01*
Y148742D01*
X244446D01*
Y148879D01*
X244583D01*
Y149016D01*
X244720D01*
Y149154D01*
X244995D01*
Y149291D01*
X245133D01*
Y149428D01*
X245270D01*
Y149566D01*
X245407D01*
Y149703D01*
X245544D01*
Y149840D01*
X245682D01*
Y149978D01*
X245819D01*
Y150115D01*
X245956D01*
Y150252D01*
X246094D01*
Y150389D01*
X246231D01*
Y150527D01*
Y150664D01*
X246368D01*
Y150801D01*
X246506D01*
Y150939D01*
X246643D01*
Y151076D01*
Y151213D01*
X246780D01*
Y151351D01*
X246918D01*
Y151488D01*
Y151625D01*
X247055D01*
Y151763D01*
Y151900D01*
X247192D01*
Y152037D01*
Y152175D01*
X247330D01*
Y152312D01*
Y152449D01*
X247467D01*
Y152587D01*
Y152724D01*
X247604D01*
Y152861D01*
Y152999D01*
Y153136D01*
X247742D01*
Y153273D01*
Y153411D01*
Y153548D01*
X247879D01*
Y153685D01*
Y153822D01*
Y153960D01*
Y154097D01*
X248016D01*
Y154234D01*
Y154372D01*
Y154509D01*
Y154646D01*
Y154784D01*
Y154921D01*
X248153D01*
Y155058D01*
Y155196D01*
Y155333D01*
Y155470D01*
Y155608D01*
Y155745D01*
Y155882D01*
Y156019D01*
Y156157D01*
Y156294D01*
Y156432D01*
Y156569D01*
Y156706D01*
Y156843D01*
Y156981D01*
Y157118D01*
X248016D01*
Y157255D01*
Y157393D01*
Y157530D01*
Y157667D01*
Y157805D01*
Y157942D01*
X247879D01*
Y158079D01*
Y158217D01*
Y158354D01*
Y158491D01*
X247742D01*
Y158629D01*
Y158766D01*
Y158903D01*
X247604D01*
Y159040D01*
Y159178D01*
Y159315D01*
X247467D01*
Y159452D01*
Y159590D01*
X247330D01*
Y159727D01*
Y159864D01*
X247192D01*
Y160002D01*
Y160139D01*
X247055D01*
Y160276D01*
Y160414D01*
X246918D01*
Y160551D01*
Y160688D01*
X246780D01*
Y160826D01*
X246643D01*
Y160963D01*
Y161100D01*
X246506D01*
Y161238D01*
X246368D01*
Y161375D01*
Y161512D01*
X246231D01*
Y161649D01*
X246094D01*
Y161787D01*
X245956D01*
Y161924D01*
X245819D01*
Y162062D01*
X245682D01*
Y162199D01*
X245544D01*
Y162336D01*
X245407D01*
Y162473D01*
X245270D01*
Y162611D01*
X245133D01*
Y162748D01*
X244995D01*
Y162885D01*
X244858D01*
Y163023D01*
X244583D01*
Y163160D01*
X244446D01*
Y163297D01*
X244309D01*
Y163435D01*
X244034D01*
Y163572D01*
X243897D01*
Y163709D01*
X243622D01*
Y163847D01*
X243347D01*
Y163984D01*
X243073D01*
Y164121D01*
X242798D01*
Y164259D01*
X242386D01*
Y164396D01*
X242111D01*
Y164533D01*
X241562D01*
Y164671D01*
X241013D01*
Y164808D01*
X240189D01*
Y164945D01*
X168921D01*
Y165082D01*
X168097D01*
Y165220D01*
X167548D01*
Y165357D01*
X167136D01*
Y165494D01*
X166724D01*
Y165632D01*
X166450D01*
Y165769D01*
X166175D01*
Y165906D01*
X165763D01*
Y166044D01*
X165626D01*
Y166181D01*
X165351D01*
Y166318D01*
X165076D01*
Y166456D01*
X164939D01*
Y166593D01*
X164664D01*
Y166730D01*
X164527D01*
Y166868D01*
X164390D01*
Y167005D01*
X164115D01*
Y167142D01*
X163978D01*
Y167280D01*
X163841D01*
Y167417D01*
X163703D01*
Y167554D01*
X163566D01*
Y167691D01*
X163429D01*
Y167829D01*
X163291D01*
Y167966D01*
X163154D01*
Y168104D01*
X163017D01*
Y168241D01*
Y168378D01*
X162879D01*
Y168515D01*
X162742D01*
Y168653D01*
X162605D01*
Y168790D01*
X162467D01*
Y168927D01*
Y169065D01*
X162330D01*
Y169202D01*
X162193D01*
Y169339D01*
Y169477D01*
X162055D01*
Y169614D01*
Y169751D01*
X161918D01*
Y169889D01*
Y170026D01*
X161781D01*
Y170163D01*
Y170301D01*
X161643D01*
Y170438D01*
Y170575D01*
X161506D01*
Y170713D01*
Y170850D01*
Y170987D01*
X161369D01*
Y171124D01*
Y171262D01*
Y171399D01*
X161231D01*
Y171536D01*
Y171674D01*
Y171811D01*
Y171948D01*
X161094D01*
Y172086D01*
Y172223D01*
Y172360D01*
Y172498D01*
Y172635D01*
X160957D01*
Y172772D01*
Y172910D01*
Y173047D01*
Y173184D01*
Y173321D01*
Y173459D01*
Y173596D01*
Y173734D01*
Y173871D01*
Y174008D01*
Y174145D01*
Y174283D01*
Y174420D01*
Y174557D01*
Y174695D01*
Y174832D01*
Y174969D01*
Y175107D01*
Y175244D01*
X161094D01*
Y175381D01*
Y175519D01*
Y175656D01*
Y175793D01*
Y175931D01*
X161231D01*
Y176068D01*
Y176205D01*
Y176343D01*
Y176480D01*
X161369D01*
Y176617D01*
Y176754D01*
Y176892D01*
X161506D01*
Y177029D01*
Y177166D01*
X161643D01*
Y177304D01*
Y177441D01*
Y177578D01*
X161781D01*
Y177716D01*
Y177853D01*
X161918D01*
Y177990D01*
Y178128D01*
X162055D01*
Y178265D01*
Y178402D01*
X162193D01*
Y178540D01*
X162330D01*
Y178677D01*
Y178814D01*
X162467D01*
Y178952D01*
X162605D01*
Y179089D01*
Y179226D01*
X162742D01*
Y179363D01*
X162879D01*
Y179501D01*
X163017D01*
Y179638D01*
X163154D01*
Y179776D01*
Y179913D01*
X163291D01*
Y180050D01*
X163429D01*
Y180187D01*
X163566D01*
Y180325D01*
X163703D01*
Y180462D01*
X163841D01*
Y180599D01*
X164115D01*
Y180737D01*
X164252D01*
Y180874D01*
X164390D01*
Y181011D01*
X164527D01*
Y181149D01*
X164802D01*
Y181286D01*
X164939D01*
Y181423D01*
X165214D01*
Y181561D01*
X165351D01*
Y181698D01*
X165626D01*
Y181835D01*
X165900D01*
Y181973D01*
X166175D01*
Y182110D01*
X166450D01*
Y182247D01*
X166861D01*
Y182384D01*
X167274D01*
Y182522D01*
X167685D01*
Y182659D01*
X168235D01*
Y182796D01*
X169196D01*
Y182934D01*
X169333D01*
Y182796D01*
X169471D01*
Y182934D01*
X278089D01*
Y183071D01*
X278775D01*
Y183208D01*
X279324D01*
Y183346D01*
X279736D01*
Y183483D01*
X280149D01*
Y183620D01*
X280423D01*
Y183758D01*
X280698D01*
Y183895D01*
X280972D01*
Y184032D01*
X281247D01*
Y184170D01*
X281522D01*
Y184307D01*
X281659D01*
Y184444D01*
X281934D01*
Y184582D01*
X282071D01*
Y184719D01*
X282346D01*
Y184856D01*
X282483D01*
Y184993D01*
X282620D01*
Y185131D01*
X282757D01*
Y185268D01*
X282895D01*
Y185406D01*
X283032D01*
Y185543D01*
X283169D01*
Y185680D01*
X283307D01*
Y185817D01*
X283444D01*
Y185955D01*
X283581D01*
Y186092D01*
X283719D01*
Y186229D01*
X283856D01*
Y186367D01*
X283993D01*
Y186504D01*
Y186641D01*
X284131D01*
Y186779D01*
X284268D01*
Y186916D01*
Y187053D01*
X284405D01*
Y187191D01*
X284543D01*
Y187328D01*
Y187465D01*
X284680D01*
Y187603D01*
Y187740D01*
X284817D01*
Y187877D01*
Y188015D01*
X284955D01*
Y188152D01*
Y188289D01*
X285092D01*
Y188426D01*
Y188564D01*
X285229D01*
Y188701D01*
Y188838D01*
Y188976D01*
X285366D01*
Y189113D01*
Y189250D01*
Y189388D01*
X285504D01*
Y189525D01*
Y189662D01*
Y189800D01*
Y189937D01*
X285641D01*
Y190074D01*
Y190212D01*
Y190349D01*
Y190486D01*
Y190623D01*
Y190761D01*
X285779D01*
Y190898D01*
Y191035D01*
Y191173D01*
Y191310D01*
Y191447D01*
Y191585D01*
Y191722D01*
Y191859D01*
Y191997D01*
Y192134D01*
Y192271D01*
Y192409D01*
Y192546D01*
Y192683D01*
Y192821D01*
Y192958D01*
X285641D01*
Y193095D01*
Y193233D01*
Y193370D01*
Y193507D01*
Y193645D01*
Y193782D01*
X285504D01*
Y193919D01*
Y194056D01*
Y194194D01*
Y194331D01*
X285366D01*
Y194468D01*
Y194606D01*
Y194743D01*
X285229D01*
Y194880D01*
Y195018D01*
X285092D01*
Y195155D01*
Y195292D01*
Y195430D01*
X284955D01*
Y195567D01*
Y195704D01*
X284817D01*
Y195842D01*
Y195979D01*
X284680D01*
Y196116D01*
Y196254D01*
X284543D01*
Y196391D01*
X284405D01*
Y196528D01*
Y196665D01*
X284268D01*
Y196803D01*
X284131D01*
Y196940D01*
Y197078D01*
X283993D01*
Y197215D01*
X283856D01*
Y197352D01*
X283719D01*
Y197489D01*
Y197627D01*
X283581D01*
Y197764D01*
X283444D01*
Y197901D01*
X283307D01*
Y198039D01*
X283169D01*
Y198176D01*
X283032D01*
Y198313D01*
X282895D01*
Y198451D01*
X282757D01*
Y198588D01*
X282483D01*
Y198725D01*
X282346D01*
Y198863D01*
X282208D01*
Y199000D01*
X282071D01*
Y199137D01*
X281796D01*
Y199275D01*
X281522D01*
Y199412D01*
X281384D01*
Y199549D01*
X281110D01*
Y199687D01*
X280835D01*
Y199824D01*
X280560D01*
Y199961D01*
X280286D01*
Y200098D01*
X279874D01*
Y200236D01*
X279599D01*
Y200373D01*
X279050D01*
Y200510D01*
X278501D01*
Y200648D01*
X277402D01*
Y200785D01*
X256667D01*
Y200922D01*
X255843D01*
Y201060D01*
X255431D01*
Y201197D01*
X254882D01*
Y201334D01*
X254607D01*
Y201472D01*
X254195D01*
Y201609D01*
X253921D01*
Y201746D01*
X253646D01*
Y201884D01*
X253372D01*
Y202021D01*
X253234D01*
Y202158D01*
X252960D01*
Y202295D01*
X252822D01*
Y202433D01*
X252548D01*
Y202570D01*
X252410D01*
Y202708D01*
X252273D01*
Y202845D01*
X251998D01*
Y202982D01*
X251861D01*
Y203119D01*
X251724D01*
Y203257D01*
X251586D01*
Y203394D01*
X251449D01*
Y203531D01*
X251312D01*
Y203669D01*
X251175D01*
Y203806D01*
X251037D01*
Y203943D01*
X250900D01*
Y204081D01*
Y204218D01*
X250763D01*
Y204355D01*
X250625D01*
Y204493D01*
X250488D01*
Y204630D01*
Y204767D01*
X250351D01*
Y204905D01*
X250213D01*
Y205042D01*
Y205179D01*
X250076D01*
Y205317D01*
X249939D01*
Y205454D01*
Y205591D01*
X249801D01*
Y205728D01*
Y205866D01*
X249664D01*
Y206003D01*
Y206140D01*
X249527D01*
Y206278D01*
Y206415D01*
Y206552D01*
X249389D01*
Y206690D01*
Y206827D01*
Y206964D01*
X249252D01*
Y207102D01*
Y207239D01*
Y207376D01*
X249115D01*
Y207514D01*
Y207651D01*
Y207788D01*
Y207925D01*
X248977D01*
Y208063D01*
Y208200D01*
Y208337D01*
Y208475D01*
Y208612D01*
Y208749D01*
Y208887D01*
X248840D01*
Y209024D01*
X248977D01*
Y209161D01*
X248840D01*
Y209299D01*
Y209436D01*
Y209573D01*
Y209711D01*
Y209848D01*
Y209985D01*
Y210123D01*
Y210260D01*
Y210397D01*
Y210535D01*
Y210672D01*
X248977D01*
Y210809D01*
Y210947D01*
Y211084D01*
Y211221D01*
Y211359D01*
Y211496D01*
X249115D01*
Y211633D01*
Y211770D01*
Y211908D01*
Y212045D01*
X249252D01*
Y212182D01*
Y212320D01*
Y212457D01*
X249389D01*
Y212594D01*
Y212732D01*
Y212869D01*
X249527D01*
Y213006D01*
Y213144D01*
Y213281D01*
X249664D01*
Y213418D01*
Y213556D01*
X249801D01*
Y213693D01*
Y213830D01*
X249939D01*
Y213967D01*
Y214105D01*
X250076D01*
Y214242D01*
X250213D01*
Y214380D01*
Y214517D01*
X250351D01*
Y214654D01*
Y214791D01*
X250488D01*
Y214929D01*
X250625D01*
Y215066D01*
X250763D01*
Y215203D01*
Y215341D01*
X250900D01*
Y215478D01*
X251037D01*
Y215615D01*
X251175D01*
Y215753D01*
X251312D01*
Y215890D01*
X251449D01*
Y216027D01*
X251586D01*
Y216165D01*
X251724D01*
Y216302D01*
X251861D01*
Y216439D01*
X251998D01*
Y216577D01*
X252136D01*
Y216714D01*
X252410D01*
Y216851D01*
X252548D01*
Y216989D01*
X252685D01*
Y217126D01*
X252960D01*
Y217263D01*
X253097D01*
Y217400D01*
X253372D01*
Y217538D01*
X253646D01*
Y217675D01*
X253921D01*
Y217812D01*
X254195D01*
Y217950D01*
X254470D01*
Y218087D01*
X254882D01*
Y218224D01*
X255294D01*
Y218362D01*
X255843D01*
Y218499D01*
X256392D01*
Y218636D01*
X257903D01*
Y218774D01*
X431198D01*
Y218636D01*
D02*
G37*
G36*
X426666Y161238D02*
X427215D01*
Y161100D01*
X427490D01*
Y160963D01*
X427902D01*
Y160826D01*
X428177D01*
Y160688D01*
X428314D01*
Y160551D01*
X428589D01*
Y160414D01*
X428726D01*
Y160276D01*
X428863D01*
Y160139D01*
X429138D01*
Y160002D01*
X429275D01*
Y159864D01*
X429413D01*
Y159727D01*
X429550D01*
Y159590D01*
Y159452D01*
X429687D01*
Y159315D01*
X429824D01*
Y159178D01*
X429962D01*
Y159040D01*
Y158903D01*
X430099D01*
Y158766D01*
Y158629D01*
X430237D01*
Y158491D01*
Y158354D01*
X430374D01*
Y158217D01*
Y158079D01*
X430511D01*
Y157942D01*
Y157805D01*
Y157667D01*
X430648D01*
Y157530D01*
Y157393D01*
Y157255D01*
Y157118D01*
Y156981D01*
X430786D01*
Y156843D01*
Y156706D01*
Y156569D01*
Y156432D01*
Y156294D01*
Y156157D01*
Y156019D01*
Y155882D01*
Y155745D01*
Y155608D01*
X430648D01*
Y155470D01*
Y155333D01*
Y155196D01*
Y155058D01*
Y154921D01*
X430511D01*
Y154784D01*
Y154646D01*
Y154509D01*
X430374D01*
Y154372D01*
Y154234D01*
Y154097D01*
X430237D01*
Y153960D01*
Y153822D01*
X430099D01*
Y153685D01*
X429962D01*
Y153548D01*
Y153411D01*
X429824D01*
Y153273D01*
Y153136D01*
X429687D01*
Y152999D01*
X429550D01*
Y152861D01*
X429413D01*
Y152724D01*
X429275D01*
Y152587D01*
X429138D01*
Y152449D01*
X429001D01*
Y152312D01*
X428863D01*
Y152175D01*
X428589D01*
Y152037D01*
X428451D01*
Y151900D01*
X428177D01*
Y151763D01*
X428039D01*
Y151625D01*
X427627D01*
Y151488D01*
X427353D01*
Y151351D01*
X426941D01*
Y151213D01*
X426117D01*
Y151076D01*
X425156D01*
Y151213D01*
X424332D01*
Y151351D01*
X423920D01*
Y151488D01*
X423508D01*
Y151625D01*
X423233D01*
Y151763D01*
X422959D01*
Y151900D01*
X422821D01*
Y152037D01*
X422547D01*
Y152175D01*
X422409D01*
Y152312D01*
X422272D01*
Y152449D01*
X422135D01*
Y152587D01*
X421997D01*
Y152724D01*
X421860D01*
Y152861D01*
X421723D01*
Y152999D01*
X421586D01*
Y153136D01*
X421448D01*
Y153273D01*
Y153411D01*
X421311D01*
Y153548D01*
X421174D01*
Y153685D01*
Y153822D01*
X421036D01*
Y153960D01*
Y154097D01*
X420899D01*
Y154234D01*
Y154372D01*
X420762D01*
Y154509D01*
Y154646D01*
Y154784D01*
X420624D01*
Y154921D01*
Y155058D01*
Y155196D01*
Y155333D01*
X420487D01*
Y155470D01*
Y155608D01*
Y155745D01*
Y155882D01*
Y156019D01*
Y156157D01*
Y156294D01*
Y156432D01*
Y156569D01*
Y156706D01*
Y156843D01*
Y156981D01*
Y157118D01*
X420624D01*
Y157255D01*
Y157393D01*
Y157530D01*
Y157667D01*
X420762D01*
Y157805D01*
Y157942D01*
Y158079D01*
X420899D01*
Y158217D01*
Y158354D01*
Y158491D01*
X421036D01*
Y158629D01*
Y158766D01*
X421174D01*
Y158903D01*
X421311D01*
Y159040D01*
Y159178D01*
X421448D01*
Y159315D01*
X421586D01*
Y159452D01*
Y159590D01*
X421723D01*
Y159727D01*
X421860D01*
Y159864D01*
X421997D01*
Y160002D01*
X422135D01*
Y160139D01*
X422272D01*
Y160276D01*
X422547D01*
Y160414D01*
X422684D01*
Y160551D01*
X422959D01*
Y160688D01*
X423096D01*
Y160826D01*
X423371D01*
Y160963D01*
X423645D01*
Y161100D01*
X424057D01*
Y161238D01*
X424607D01*
Y161375D01*
X426666D01*
Y161238D01*
D02*
G37*
G36*
X426392Y142700D02*
X427078D01*
Y142562D01*
X427490D01*
Y142425D01*
X427765D01*
Y142288D01*
X428039D01*
Y142150D01*
X428314D01*
Y142013D01*
X428451D01*
Y141876D01*
X428726D01*
Y141739D01*
X428863D01*
Y141601D01*
X429001D01*
Y141464D01*
X429138D01*
Y141327D01*
X429275D01*
Y141189D01*
X429413D01*
Y141052D01*
X429550D01*
Y140915D01*
X429687D01*
Y140777D01*
X429824D01*
Y140640D01*
Y140503D01*
X429962D01*
Y140365D01*
X430099D01*
Y140228D01*
Y140091D01*
X430237D01*
Y139953D01*
Y139816D01*
X430374D01*
Y139679D01*
Y139541D01*
X430511D01*
Y139404D01*
Y139267D01*
Y139129D01*
Y138992D01*
X430648D01*
Y138855D01*
Y138717D01*
Y138580D01*
Y138443D01*
X430786D01*
Y138306D01*
Y138168D01*
Y138031D01*
Y137894D01*
Y137756D01*
Y137619D01*
Y137482D01*
Y137344D01*
Y137207D01*
Y137070D01*
Y136932D01*
X430648D01*
Y136795D01*
Y136658D01*
Y136520D01*
Y136383D01*
X430511D01*
Y136246D01*
Y136109D01*
Y135971D01*
X430374D01*
Y135834D01*
Y135696D01*
Y135559D01*
X430237D01*
Y135422D01*
Y135285D01*
X430099D01*
Y135147D01*
Y135010D01*
X429962D01*
Y134873D01*
X429824D01*
Y134735D01*
Y134598D01*
X429687D01*
Y134461D01*
X429550D01*
Y134323D01*
X429413D01*
Y134186D01*
X429275D01*
Y134049D01*
X429138D01*
Y133911D01*
X429001D01*
Y133774D01*
X428863D01*
Y133637D01*
X428726D01*
Y133499D01*
X428451D01*
Y133362D01*
X428314D01*
Y133225D01*
X428039D01*
Y133088D01*
X427765D01*
Y132950D01*
X427490D01*
Y132813D01*
X427078D01*
Y132676D01*
X426392D01*
Y132538D01*
X424881D01*
Y132676D01*
X424194D01*
Y132813D01*
X423783D01*
Y132950D01*
X423508D01*
Y133088D01*
X423233D01*
Y133225D01*
X422959D01*
Y133362D01*
X422684D01*
Y133499D01*
X422547D01*
Y133637D01*
X422409D01*
Y133774D01*
X422272D01*
Y133911D01*
X421997D01*
Y134049D01*
X421860D01*
Y134186D01*
X421723D01*
Y134323D01*
Y134461D01*
X421586D01*
Y134598D01*
X421448D01*
Y134735D01*
X421311D01*
Y134873D01*
Y135010D01*
X421174D01*
Y135147D01*
Y135285D01*
X421036D01*
Y135422D01*
Y135559D01*
X420899D01*
Y135696D01*
Y135834D01*
X420762D01*
Y135971D01*
Y136109D01*
Y136246D01*
X420624D01*
Y136383D01*
Y136520D01*
Y136658D01*
Y136795D01*
X420487D01*
Y136932D01*
Y137070D01*
Y137207D01*
Y137344D01*
Y137482D01*
Y137619D01*
Y137756D01*
Y137894D01*
Y138031D01*
Y138168D01*
Y138306D01*
Y138443D01*
Y138580D01*
X420624D01*
Y138717D01*
Y138855D01*
Y138992D01*
Y139129D01*
X420762D01*
Y139267D01*
Y139404D01*
Y139541D01*
X420899D01*
Y139679D01*
Y139816D01*
X421036D01*
Y139953D01*
Y140091D01*
X421174D01*
Y140228D01*
Y140365D01*
X421311D01*
Y140503D01*
Y140640D01*
X421448D01*
Y140777D01*
X421586D01*
Y140915D01*
X421723D01*
Y141052D01*
Y141189D01*
X421860D01*
Y141327D01*
X421997D01*
Y141464D01*
X422135D01*
Y141601D01*
X422409D01*
Y141739D01*
X422547D01*
Y141876D01*
X422684D01*
Y142013D01*
X422959D01*
Y142150D01*
X423233D01*
Y142288D01*
X423508D01*
Y142425D01*
X423783D01*
Y142562D01*
X424194D01*
Y142700D01*
X424744D01*
Y142837D01*
X426392D01*
Y142700D01*
D02*
G37*
G36*
X187459Y146957D02*
X188146D01*
Y146819D01*
X188695D01*
Y146682D01*
X189107D01*
Y146545D01*
X189519D01*
Y146407D01*
X189931D01*
Y146270D01*
X190205D01*
Y146133D01*
X190480D01*
Y145995D01*
X190755D01*
Y145858D01*
X190892D01*
Y145721D01*
X191167D01*
Y145583D01*
X191304D01*
Y145446D01*
X191579D01*
Y145309D01*
X191716D01*
Y145171D01*
X191991D01*
Y145034D01*
X192128D01*
Y144897D01*
X192265D01*
Y144760D01*
X192403D01*
Y144622D01*
X192540D01*
Y144485D01*
X192677D01*
Y144347D01*
X192815D01*
Y144210D01*
X192952D01*
Y144073D01*
X193089D01*
Y143936D01*
X193227D01*
Y143798D01*
X193364D01*
Y143661D01*
Y143524D01*
X193501D01*
Y143386D01*
X193638D01*
Y143249D01*
X193776D01*
Y143112D01*
Y142974D01*
X193913D01*
Y142837D01*
X194050D01*
Y142700D01*
Y142562D01*
X194188D01*
Y142425D01*
Y142288D01*
X194325D01*
Y142150D01*
Y142013D01*
X194462D01*
Y141876D01*
Y141739D01*
X194600D01*
Y141601D01*
Y141464D01*
X194737D01*
Y141327D01*
Y141189D01*
Y141052D01*
X194874D01*
Y140915D01*
Y140777D01*
Y140640D01*
X195012D01*
Y140503D01*
Y140365D01*
Y140228D01*
Y140091D01*
X195149D01*
Y139953D01*
Y139816D01*
Y139679D01*
Y139541D01*
Y139404D01*
X195286D01*
Y139267D01*
Y139129D01*
Y138992D01*
Y138855D01*
Y138717D01*
Y138580D01*
Y138443D01*
Y138306D01*
Y138168D01*
Y138031D01*
Y137894D01*
Y137756D01*
Y137619D01*
Y137482D01*
Y137344D01*
Y137207D01*
Y137070D01*
Y136932D01*
Y136795D01*
X195149D01*
Y136658D01*
Y136520D01*
Y136383D01*
Y136246D01*
Y136109D01*
X195012D01*
Y135971D01*
Y135834D01*
Y135696D01*
Y135559D01*
X194874D01*
Y135422D01*
Y135285D01*
Y135147D01*
X194737D01*
Y135010D01*
Y134873D01*
X194600D01*
Y134735D01*
Y134598D01*
Y134461D01*
X194462D01*
Y134323D01*
Y134186D01*
X194325D01*
Y134049D01*
Y133911D01*
X194188D01*
Y133774D01*
X194050D01*
Y133637D01*
Y133499D01*
X193913D01*
Y133362D01*
Y133225D01*
X193776D01*
Y133088D01*
X193638D01*
Y132950D01*
Y132813D01*
X193501D01*
Y132676D01*
X193364D01*
Y132538D01*
X193227D01*
Y132401D01*
X193089D01*
Y132264D01*
Y132126D01*
X192952D01*
Y131989D01*
X192815D01*
Y131852D01*
X192677D01*
Y131714D01*
X192540D01*
Y131577D01*
X192403D01*
Y131440D01*
X192128D01*
Y131302D01*
X191991D01*
Y131165D01*
X191853D01*
Y131028D01*
X191716D01*
Y130890D01*
X191441D01*
Y130753D01*
X191304D01*
Y130616D01*
X191029D01*
Y130478D01*
X190892D01*
Y130341D01*
X190617D01*
Y130204D01*
X190343D01*
Y130066D01*
X190068D01*
Y129929D01*
X189793D01*
Y129792D01*
X189382D01*
Y129655D01*
X188970D01*
Y129517D01*
X188558D01*
Y129380D01*
X187871D01*
Y129243D01*
X186910D01*
Y129105D01*
X185949D01*
Y129243D01*
X185811D01*
Y129105D01*
X185674D01*
Y129243D01*
X185537D01*
Y129105D01*
X185399D01*
Y129243D01*
X184576D01*
Y129380D01*
X183889D01*
Y129517D01*
X183340D01*
Y129655D01*
X182928D01*
Y129792D01*
X182653D01*
Y129929D01*
X182241D01*
Y130066D01*
X181966D01*
Y130204D01*
X181692D01*
Y130341D01*
X181555D01*
Y130478D01*
X181280D01*
Y130616D01*
X181005D01*
Y130753D01*
X180868D01*
Y130890D01*
X180731D01*
Y131028D01*
X180456D01*
Y131165D01*
X180319D01*
Y131302D01*
X180181D01*
Y131440D01*
X180044D01*
Y131577D01*
X179907D01*
Y131714D01*
X179769D01*
Y131852D01*
X179632D01*
Y131989D01*
X179495D01*
Y132126D01*
X179357D01*
Y132264D01*
X179220D01*
Y132401D01*
X179083D01*
Y132538D01*
X178945D01*
Y132676D01*
X178808D01*
Y132813D01*
Y132950D01*
X178671D01*
Y133088D01*
X178533D01*
Y133225D01*
Y133362D01*
X178396D01*
Y133499D01*
X178259D01*
Y133637D01*
Y133774D01*
X178121D01*
Y133911D01*
Y134049D01*
X177984D01*
Y134186D01*
Y134323D01*
X177847D01*
Y134461D01*
Y134598D01*
X177710D01*
Y134735D01*
Y134873D01*
X177572D01*
Y135010D01*
Y135147D01*
Y135285D01*
X177435D01*
Y135422D01*
Y135559D01*
Y135696D01*
X177298D01*
Y135834D01*
Y135971D01*
Y136109D01*
Y136246D01*
X177160D01*
Y136383D01*
Y136520D01*
Y136658D01*
Y136795D01*
Y136932D01*
Y137070D01*
X177023D01*
Y137207D01*
Y137344D01*
Y137482D01*
Y137619D01*
Y137756D01*
Y137894D01*
Y138031D01*
Y138168D01*
Y138306D01*
Y138443D01*
Y138580D01*
Y138717D01*
Y138855D01*
Y138992D01*
Y139129D01*
X177160D01*
Y139267D01*
Y139404D01*
Y139541D01*
Y139679D01*
Y139816D01*
Y139953D01*
X177298D01*
Y140091D01*
Y140228D01*
Y140365D01*
Y140503D01*
X177435D01*
Y140640D01*
Y140777D01*
Y140915D01*
X177572D01*
Y141052D01*
Y141189D01*
Y141327D01*
X177710D01*
Y141464D01*
Y141601D01*
X177847D01*
Y141739D01*
Y141876D01*
Y142013D01*
X177984D01*
Y142150D01*
Y142288D01*
X178121D01*
Y142425D01*
X178259D01*
Y142562D01*
Y142700D01*
X178396D01*
Y142837D01*
Y142974D01*
X178533D01*
Y143112D01*
X178671D01*
Y143249D01*
Y143386D01*
X178808D01*
Y143524D01*
X178945D01*
Y143661D01*
X179083D01*
Y143798D01*
Y143936D01*
X179220D01*
Y144073D01*
X179357D01*
Y144210D01*
X179495D01*
Y144347D01*
X179632D01*
Y144485D01*
X179769D01*
Y144622D01*
X179907D01*
Y144760D01*
X180044D01*
Y144897D01*
X180319D01*
Y145034D01*
X180456D01*
Y145171D01*
X180593D01*
Y145309D01*
X180731D01*
Y145446D01*
X181005D01*
Y145583D01*
X181143D01*
Y145721D01*
X181417D01*
Y145858D01*
X181692D01*
Y145995D01*
X181829D01*
Y146133D01*
X182104D01*
Y146270D01*
X182516D01*
Y146407D01*
X182790D01*
Y146545D01*
X183202D01*
Y146682D01*
X183614D01*
Y146819D01*
X184163D01*
Y146957D01*
X184987D01*
Y147094D01*
X187459D01*
Y146957D01*
D02*
G37*
G36*
X426254Y124162D02*
X426941D01*
Y124024D01*
X427353D01*
Y123887D01*
X427765D01*
Y123750D01*
X428039D01*
Y123613D01*
X428177D01*
Y123475D01*
X428451D01*
Y123338D01*
X428726D01*
Y123201D01*
X428863D01*
Y123063D01*
X429001D01*
Y122926D01*
X429138D01*
Y122789D01*
X429275D01*
Y122651D01*
X429413D01*
Y122514D01*
X429550D01*
Y122377D01*
X429687D01*
Y122239D01*
X429824D01*
Y122102D01*
Y121965D01*
X429962D01*
Y121827D01*
X430099D01*
Y121690D01*
Y121553D01*
X430237D01*
Y121416D01*
Y121278D01*
X430374D01*
Y121141D01*
Y121004D01*
Y120866D01*
X430511D01*
Y120729D01*
Y120592D01*
Y120454D01*
X430648D01*
Y120317D01*
Y120180D01*
Y120042D01*
Y119905D01*
Y119768D01*
X430786D01*
Y119630D01*
Y119493D01*
Y119356D01*
Y119218D01*
Y119081D01*
Y118944D01*
Y118806D01*
Y118669D01*
Y118532D01*
Y118394D01*
X430648D01*
Y118257D01*
Y118120D01*
Y117983D01*
Y117845D01*
Y117708D01*
X430511D01*
Y117571D01*
Y117433D01*
Y117296D01*
X430374D01*
Y117159D01*
Y117021D01*
X430237D01*
Y116884D01*
Y116747D01*
X430099D01*
Y116609D01*
Y116472D01*
X429962D01*
Y116335D01*
Y116198D01*
X429824D01*
Y116060D01*
X429687D01*
Y115923D01*
X429550D01*
Y115786D01*
Y115648D01*
X429413D01*
Y115511D01*
X429275D01*
Y115373D01*
X429138D01*
Y115236D01*
X428863D01*
Y115099D01*
X428726D01*
Y114962D01*
X428589D01*
Y114824D01*
X428314D01*
Y114687D01*
X428039D01*
Y114550D01*
X427902D01*
Y114412D01*
X427490D01*
Y114275D01*
X427078D01*
Y114138D01*
X426666D01*
Y114000D01*
X424607D01*
Y114138D01*
X424057D01*
Y114275D01*
X423783D01*
Y114412D01*
X423371D01*
Y114550D01*
X423096D01*
Y114687D01*
X422959D01*
Y114824D01*
X422684D01*
Y114962D01*
X422547D01*
Y115099D01*
X422272D01*
Y115236D01*
X422135D01*
Y115373D01*
X421997D01*
Y115511D01*
X421860D01*
Y115648D01*
X421723D01*
Y115786D01*
X421586D01*
Y115923D01*
Y116060D01*
X421448D01*
Y116198D01*
X421311D01*
Y116335D01*
Y116472D01*
X421174D01*
Y116609D01*
X421036D01*
Y116747D01*
Y116884D01*
X420899D01*
Y117021D01*
Y117159D01*
Y117296D01*
X420762D01*
Y117433D01*
Y117571D01*
Y117708D01*
X420624D01*
Y117845D01*
Y117983D01*
Y118120D01*
Y118257D01*
X420487D01*
Y118394D01*
Y118532D01*
Y118669D01*
Y118806D01*
Y118944D01*
Y119081D01*
Y119218D01*
Y119356D01*
Y119493D01*
Y119630D01*
Y119768D01*
Y119905D01*
Y120042D01*
X420624D01*
Y120180D01*
Y120317D01*
Y120454D01*
Y120592D01*
X420762D01*
Y120729D01*
Y120866D01*
Y121004D01*
X420899D01*
Y121141D01*
Y121278D01*
X421036D01*
Y121416D01*
Y121553D01*
X421174D01*
Y121690D01*
Y121827D01*
X421311D01*
Y121965D01*
X421448D01*
Y122102D01*
Y122239D01*
X421586D01*
Y122377D01*
X421723D01*
Y122514D01*
X421860D01*
Y122651D01*
X421997D01*
Y122789D01*
X422135D01*
Y122926D01*
X422272D01*
Y123063D01*
X422409D01*
Y123201D01*
X422547D01*
Y123338D01*
X422821D01*
Y123475D01*
X422959D01*
Y123613D01*
X423233D01*
Y123750D01*
X423508D01*
Y123887D01*
X423920D01*
Y124024D01*
X424332D01*
Y124162D01*
X425018D01*
Y124299D01*
X426254D01*
Y124162D01*
D02*
G37*
G36*
X426804Y105487D02*
X427215D01*
Y105349D01*
X427627D01*
Y105212D01*
X427902D01*
Y105075D01*
X428177D01*
Y104937D01*
X428451D01*
Y104800D01*
X428589D01*
Y104663D01*
X428863D01*
Y104525D01*
X429001D01*
Y104388D01*
X429138D01*
Y104251D01*
X429275D01*
Y104114D01*
X429413D01*
Y103976D01*
X429550D01*
Y103839D01*
X429687D01*
Y103701D01*
Y103564D01*
X429824D01*
Y103427D01*
X429962D01*
Y103290D01*
Y103152D01*
X430099D01*
Y103015D01*
Y102878D01*
X430237D01*
Y102740D01*
Y102603D01*
X430374D01*
Y102466D01*
Y102328D01*
X430511D01*
Y102191D01*
Y102054D01*
Y101916D01*
X430648D01*
Y101779D01*
Y101642D01*
Y101504D01*
Y101367D01*
Y101230D01*
X430786D01*
Y101093D01*
Y100955D01*
Y100818D01*
Y100681D01*
Y100543D01*
Y100406D01*
Y100269D01*
Y100131D01*
Y99994D01*
Y99857D01*
X430648D01*
Y99719D01*
Y99582D01*
Y99445D01*
Y99307D01*
Y99170D01*
X430511D01*
Y99033D01*
Y98895D01*
Y98758D01*
X430374D01*
Y98621D01*
Y98483D01*
X430237D01*
Y98346D01*
Y98209D01*
X430099D01*
Y98071D01*
Y97934D01*
X429962D01*
Y97797D01*
Y97660D01*
X429824D01*
Y97522D01*
X429687D01*
Y97385D01*
Y97248D01*
X429550D01*
Y97110D01*
X429413D01*
Y96973D01*
X429275D01*
Y96836D01*
X429138D01*
Y96698D01*
X429001D01*
Y96561D01*
X428726D01*
Y96424D01*
X428589D01*
Y96286D01*
X428451D01*
Y96149D01*
X428177D01*
Y96012D01*
X427902D01*
Y95875D01*
X427627D01*
Y95737D01*
X427215D01*
Y95600D01*
X426804D01*
Y95463D01*
X424469D01*
Y95600D01*
X424057D01*
Y95737D01*
X423645D01*
Y95875D01*
X423371D01*
Y96012D01*
X423096D01*
Y96149D01*
X422821D01*
Y96286D01*
X422684D01*
Y96424D01*
X422409D01*
Y96561D01*
X422272D01*
Y96698D01*
X422135D01*
Y96836D01*
X421997D01*
Y96973D01*
X421860D01*
Y97110D01*
X421723D01*
Y97248D01*
X421586D01*
Y97385D01*
X421448D01*
Y97522D01*
Y97660D01*
X421311D01*
Y97797D01*
X421174D01*
Y97934D01*
Y98071D01*
X421036D01*
Y98209D01*
Y98346D01*
X420899D01*
Y98483D01*
Y98621D01*
X420762D01*
Y98758D01*
Y98895D01*
Y99033D01*
X420624D01*
Y99170D01*
Y99307D01*
Y99445D01*
Y99582D01*
Y99719D01*
X420487D01*
Y99857D01*
Y99994D01*
Y100131D01*
Y100269D01*
Y100406D01*
Y100543D01*
Y100681D01*
Y100818D01*
Y100955D01*
Y101093D01*
Y101230D01*
Y101367D01*
X420624D01*
Y101504D01*
Y101642D01*
Y101779D01*
Y101916D01*
Y102054D01*
X420762D01*
Y102191D01*
Y102328D01*
Y102466D01*
X420899D01*
Y102603D01*
Y102740D01*
X421036D01*
Y102878D01*
Y103015D01*
X421174D01*
Y103152D01*
Y103290D01*
X421311D01*
Y103427D01*
X421448D01*
Y103564D01*
Y103701D01*
X421586D01*
Y103839D01*
X421723D01*
Y103976D01*
X421860D01*
Y104114D01*
X421997D01*
Y104251D01*
X422135D01*
Y104388D01*
X422272D01*
Y104525D01*
X422409D01*
Y104663D01*
X422684D01*
Y104800D01*
X422821D01*
Y104937D01*
X423096D01*
Y105075D01*
X423371D01*
Y105212D01*
X423645D01*
Y105349D01*
X423920D01*
Y105487D01*
X424469D01*
Y105624D01*
X426804D01*
Y105487D01*
D02*
G37*
G36*
X461957Y218636D02*
Y218499D01*
Y218362D01*
Y218224D01*
Y218087D01*
Y217950D01*
Y217812D01*
Y217675D01*
Y217538D01*
Y217400D01*
Y217263D01*
Y217126D01*
Y216989D01*
Y216851D01*
Y216714D01*
Y216577D01*
Y216439D01*
Y216302D01*
Y216165D01*
Y216027D01*
Y215890D01*
Y215753D01*
Y215615D01*
Y215478D01*
Y215341D01*
Y215203D01*
Y215066D01*
Y214929D01*
Y214791D01*
Y214654D01*
Y214517D01*
Y214380D01*
Y214242D01*
Y214105D01*
Y213967D01*
Y213830D01*
Y213693D01*
Y213556D01*
X444518D01*
Y213418D01*
X443968D01*
Y213281D01*
X443694D01*
Y213144D01*
X443419D01*
Y213006D01*
X443144D01*
Y212869D01*
X443007D01*
Y212732D01*
X442732D01*
Y212594D01*
X442595D01*
Y212457D01*
X442458D01*
Y212320D01*
X442320D01*
Y212182D01*
Y212045D01*
X442183D01*
Y211908D01*
X442046D01*
Y211770D01*
Y211633D01*
X441908D01*
Y211496D01*
Y211359D01*
X441771D01*
Y211221D01*
Y211084D01*
X441634D01*
Y210947D01*
Y210809D01*
Y210672D01*
Y210535D01*
Y210397D01*
X441497D01*
Y210260D01*
Y210123D01*
Y209985D01*
Y209848D01*
Y209711D01*
Y209573D01*
Y209436D01*
Y209299D01*
Y209161D01*
Y209024D01*
Y208887D01*
Y208749D01*
Y208612D01*
Y208475D01*
Y208337D01*
Y208200D01*
Y208063D01*
Y207925D01*
Y207788D01*
Y207651D01*
Y207514D01*
Y207376D01*
Y207239D01*
Y207102D01*
Y206964D01*
Y206827D01*
Y206690D01*
Y206552D01*
Y206415D01*
Y206278D01*
Y206140D01*
Y206003D01*
Y205866D01*
Y205728D01*
Y205591D01*
Y205454D01*
Y205317D01*
Y205179D01*
Y205042D01*
Y204905D01*
Y204767D01*
Y204630D01*
Y204493D01*
Y204355D01*
Y204218D01*
Y204081D01*
Y203943D01*
Y203806D01*
Y203669D01*
Y203531D01*
Y203394D01*
Y203257D01*
Y203119D01*
Y202982D01*
Y202845D01*
Y202708D01*
Y202570D01*
Y202433D01*
Y202295D01*
Y202158D01*
Y202021D01*
Y201884D01*
Y201746D01*
Y201609D01*
Y201472D01*
Y201334D01*
Y201197D01*
Y201060D01*
Y200922D01*
Y200785D01*
Y200648D01*
Y200510D01*
Y200373D01*
Y200236D01*
Y200098D01*
Y199961D01*
Y199824D01*
Y199687D01*
Y199549D01*
Y199412D01*
Y199275D01*
Y199137D01*
Y199000D01*
Y198863D01*
Y198725D01*
Y198588D01*
Y198451D01*
Y198313D01*
Y198176D01*
Y198039D01*
Y197901D01*
Y197764D01*
Y197627D01*
Y197489D01*
Y197352D01*
Y197215D01*
Y197078D01*
Y196940D01*
Y196803D01*
Y196665D01*
Y196528D01*
Y196391D01*
Y196254D01*
Y196116D01*
Y195979D01*
Y195842D01*
Y195704D01*
Y195567D01*
Y195430D01*
Y195292D01*
Y195155D01*
Y195018D01*
Y194880D01*
Y194743D01*
Y194606D01*
Y194468D01*
Y194331D01*
Y194194D01*
Y194056D01*
Y193919D01*
Y193782D01*
Y193645D01*
Y193507D01*
Y193370D01*
Y193233D01*
Y193095D01*
Y192958D01*
Y192821D01*
Y192683D01*
Y192546D01*
Y192409D01*
Y192271D01*
Y192134D01*
Y191997D01*
Y191859D01*
Y191722D01*
Y191585D01*
Y191447D01*
Y191310D01*
Y191173D01*
Y191035D01*
Y190898D01*
Y190761D01*
Y190623D01*
Y190486D01*
Y190349D01*
Y190212D01*
Y190074D01*
Y189937D01*
Y189800D01*
Y189662D01*
Y189525D01*
Y189388D01*
Y189250D01*
Y189113D01*
Y188976D01*
Y188838D01*
Y188701D01*
Y188564D01*
Y188426D01*
Y188289D01*
Y188152D01*
Y188015D01*
Y187877D01*
Y187740D01*
Y187603D01*
Y187465D01*
Y187328D01*
Y187191D01*
Y187053D01*
Y186916D01*
Y186779D01*
Y186641D01*
Y186504D01*
Y186367D01*
Y186229D01*
Y186092D01*
Y185955D01*
Y185817D01*
Y185680D01*
Y185543D01*
Y185406D01*
Y185268D01*
Y185131D01*
Y184993D01*
Y184856D01*
Y184719D01*
Y184582D01*
Y184444D01*
Y184307D01*
Y184170D01*
Y184032D01*
Y183895D01*
Y183758D01*
Y183620D01*
Y183483D01*
Y183346D01*
Y183208D01*
Y183071D01*
Y182934D01*
Y182796D01*
Y182659D01*
Y182522D01*
Y182384D01*
Y182247D01*
Y182110D01*
Y181973D01*
Y181835D01*
Y181698D01*
Y181561D01*
Y181423D01*
Y181286D01*
Y181149D01*
Y181011D01*
Y180874D01*
Y180737D01*
Y180599D01*
Y180462D01*
Y180325D01*
Y180187D01*
Y180050D01*
Y179913D01*
Y179776D01*
Y179638D01*
Y179501D01*
Y179363D01*
Y179226D01*
Y179089D01*
Y178952D01*
Y178814D01*
Y178677D01*
Y178540D01*
Y178402D01*
Y178265D01*
Y178128D01*
Y177990D01*
Y177853D01*
Y177716D01*
Y177578D01*
Y177441D01*
Y177304D01*
Y177166D01*
Y177029D01*
Y176892D01*
Y176754D01*
Y176617D01*
Y176480D01*
Y176343D01*
Y176205D01*
Y176068D01*
Y175931D01*
Y175793D01*
Y175656D01*
Y175519D01*
Y175381D01*
Y175244D01*
Y175107D01*
Y174969D01*
Y174832D01*
Y174695D01*
Y174557D01*
Y174420D01*
Y174283D01*
Y174145D01*
Y174008D01*
Y173871D01*
Y173734D01*
Y173596D01*
Y173459D01*
Y173321D01*
Y173184D01*
Y173047D01*
Y172910D01*
Y172772D01*
Y172635D01*
Y172498D01*
Y172360D01*
Y172223D01*
Y172086D01*
Y171948D01*
Y171811D01*
Y171674D01*
Y171536D01*
Y171399D01*
Y171262D01*
Y171124D01*
Y170987D01*
Y170850D01*
Y170713D01*
Y170575D01*
Y170438D01*
Y170301D01*
Y170163D01*
Y170026D01*
Y169889D01*
Y169751D01*
Y169614D01*
Y169477D01*
Y169339D01*
Y169202D01*
Y169065D01*
Y168927D01*
Y168790D01*
Y168653D01*
Y168515D01*
Y168378D01*
Y168241D01*
Y168104D01*
Y167966D01*
Y167829D01*
Y167691D01*
Y167554D01*
Y167417D01*
Y167280D01*
Y167142D01*
Y167005D01*
Y166868D01*
Y166730D01*
Y166593D01*
Y166456D01*
Y166318D01*
Y166181D01*
Y166044D01*
Y165906D01*
Y165769D01*
Y165632D01*
Y165494D01*
Y165357D01*
Y165220D01*
Y165082D01*
Y164945D01*
Y164808D01*
Y164671D01*
Y164533D01*
Y164396D01*
Y164259D01*
Y164121D01*
Y163984D01*
Y163847D01*
Y163709D01*
Y163572D01*
Y163435D01*
Y163297D01*
Y163160D01*
Y163023D01*
Y162885D01*
Y162748D01*
Y162611D01*
Y162473D01*
Y162336D01*
Y162199D01*
Y162062D01*
Y161924D01*
Y161787D01*
Y161649D01*
Y161512D01*
Y161375D01*
Y161238D01*
Y161100D01*
Y160963D01*
Y160826D01*
Y160688D01*
Y160551D01*
Y160414D01*
Y160276D01*
Y160139D01*
Y160002D01*
Y159864D01*
Y159727D01*
Y159590D01*
Y159452D01*
Y159315D01*
Y159178D01*
Y159040D01*
Y158903D01*
Y158766D01*
Y158629D01*
Y158491D01*
Y158354D01*
Y158217D01*
Y158079D01*
Y157942D01*
Y157805D01*
Y157667D01*
Y157530D01*
Y157393D01*
Y157255D01*
Y157118D01*
Y156981D01*
Y156843D01*
Y156706D01*
Y156569D01*
Y156432D01*
Y156294D01*
Y156157D01*
Y156019D01*
Y155882D01*
Y155745D01*
Y155608D01*
Y155470D01*
Y155333D01*
Y155196D01*
Y155058D01*
Y154921D01*
Y154784D01*
Y154646D01*
Y154509D01*
Y154372D01*
Y154234D01*
Y154097D01*
Y153960D01*
Y153822D01*
Y153685D01*
Y153548D01*
Y153411D01*
Y153273D01*
Y153136D01*
Y152999D01*
Y152861D01*
Y152724D01*
Y152587D01*
Y152449D01*
Y152312D01*
Y152175D01*
Y152037D01*
Y151900D01*
Y151763D01*
Y151625D01*
Y151488D01*
Y151351D01*
Y151213D01*
Y151076D01*
Y150939D01*
Y150801D01*
Y150664D01*
Y150527D01*
Y150389D01*
Y150252D01*
Y150115D01*
Y149978D01*
Y149840D01*
Y149703D01*
Y149566D01*
Y149428D01*
Y149291D01*
Y149154D01*
Y149016D01*
Y148879D01*
Y148742D01*
Y148604D01*
Y148467D01*
Y148330D01*
Y148192D01*
Y148055D01*
Y147918D01*
Y147781D01*
Y147643D01*
Y147506D01*
Y147368D01*
Y147231D01*
Y147094D01*
Y146957D01*
Y146819D01*
Y146682D01*
Y146545D01*
Y146407D01*
Y146270D01*
Y146133D01*
Y145995D01*
Y145858D01*
Y145721D01*
Y145583D01*
Y145446D01*
Y145309D01*
Y145171D01*
Y145034D01*
Y144897D01*
Y144760D01*
Y144622D01*
Y144485D01*
Y144347D01*
Y144210D01*
Y144073D01*
Y143936D01*
Y143798D01*
Y143661D01*
Y143524D01*
Y143386D01*
Y143249D01*
Y143112D01*
Y142974D01*
Y142837D01*
Y142700D01*
Y142562D01*
Y142425D01*
Y142288D01*
Y142150D01*
Y142013D01*
Y141876D01*
Y141739D01*
Y141601D01*
Y141464D01*
Y141327D01*
Y141189D01*
Y141052D01*
Y140915D01*
Y140777D01*
Y140640D01*
Y140503D01*
Y140365D01*
Y140228D01*
Y140091D01*
Y139953D01*
Y139816D01*
Y139679D01*
Y139541D01*
Y139404D01*
Y139267D01*
Y139129D01*
Y138992D01*
Y138855D01*
Y138717D01*
Y138580D01*
Y138443D01*
Y138306D01*
Y138168D01*
Y138031D01*
Y137894D01*
Y137756D01*
Y137619D01*
Y137482D01*
Y137344D01*
Y137207D01*
Y137070D01*
Y136932D01*
Y136795D01*
Y136658D01*
Y136520D01*
Y136383D01*
Y136246D01*
Y136109D01*
Y135971D01*
Y135834D01*
Y135696D01*
Y135559D01*
Y135422D01*
Y135285D01*
Y135147D01*
Y135010D01*
Y134873D01*
Y134735D01*
Y134598D01*
Y134461D01*
Y134323D01*
Y134186D01*
Y134049D01*
Y133911D01*
Y133774D01*
Y133637D01*
Y133499D01*
Y133362D01*
Y133225D01*
Y133088D01*
Y132950D01*
Y132813D01*
Y132676D01*
Y132538D01*
Y132401D01*
Y132264D01*
Y132126D01*
Y131989D01*
Y131852D01*
Y131714D01*
Y131577D01*
Y131440D01*
Y131302D01*
Y131165D01*
Y131028D01*
Y130890D01*
Y130753D01*
Y130616D01*
Y130478D01*
Y130341D01*
Y130204D01*
Y130066D01*
Y129929D01*
Y129792D01*
Y129655D01*
Y129517D01*
Y129380D01*
Y129243D01*
Y129105D01*
Y128968D01*
Y128831D01*
Y128693D01*
Y128556D01*
Y128419D01*
Y128281D01*
Y128144D01*
Y128007D01*
Y127869D01*
Y127732D01*
Y127595D01*
Y127458D01*
Y127320D01*
Y127183D01*
Y127045D01*
Y126908D01*
Y126771D01*
Y126634D01*
Y126496D01*
Y126359D01*
Y126222D01*
Y126084D01*
Y125947D01*
Y125810D01*
Y125672D01*
Y125535D01*
Y125398D01*
Y125260D01*
Y125123D01*
Y124986D01*
Y124848D01*
Y124711D01*
Y124574D01*
Y124437D01*
Y124299D01*
Y124162D01*
Y124024D01*
Y123887D01*
Y123750D01*
Y123613D01*
Y123475D01*
Y123338D01*
Y123201D01*
Y123063D01*
Y122926D01*
Y122789D01*
Y122651D01*
Y122514D01*
Y122377D01*
Y122239D01*
Y122102D01*
Y121965D01*
Y121827D01*
Y121690D01*
Y121553D01*
Y121416D01*
Y121278D01*
Y121141D01*
Y121004D01*
Y120866D01*
Y120729D01*
Y120592D01*
Y120454D01*
Y120317D01*
Y120180D01*
Y120042D01*
Y119905D01*
Y119768D01*
Y119630D01*
Y119493D01*
Y119356D01*
Y119218D01*
Y119081D01*
Y118944D01*
Y118806D01*
Y118669D01*
Y118532D01*
Y118394D01*
Y118257D01*
Y118120D01*
Y117983D01*
Y117845D01*
Y117708D01*
Y117571D01*
Y117433D01*
Y117296D01*
Y117159D01*
Y117021D01*
Y116884D01*
Y116747D01*
Y116609D01*
Y116472D01*
Y116335D01*
Y116198D01*
Y116060D01*
Y115923D01*
Y115786D01*
Y115648D01*
Y115511D01*
Y115373D01*
Y115236D01*
Y115099D01*
Y114962D01*
Y114824D01*
Y114687D01*
Y114550D01*
Y114412D01*
Y114275D01*
Y114138D01*
Y114000D01*
Y113863D01*
Y113726D01*
Y113588D01*
Y113451D01*
Y113314D01*
Y113176D01*
Y113039D01*
Y112902D01*
Y112765D01*
Y112627D01*
Y112490D01*
Y112353D01*
Y112215D01*
Y112078D01*
Y111941D01*
Y111803D01*
Y111666D01*
Y111529D01*
Y111391D01*
Y111254D01*
Y111117D01*
Y110979D01*
Y110842D01*
Y110705D01*
Y110567D01*
Y110430D01*
Y110293D01*
Y110155D01*
Y110018D01*
Y109881D01*
Y109743D01*
Y109606D01*
Y109469D01*
Y109332D01*
Y109194D01*
Y109057D01*
Y108920D01*
Y108782D01*
Y108645D01*
Y108508D01*
Y108370D01*
Y108233D01*
Y108096D01*
Y107958D01*
Y107821D01*
Y107684D01*
Y107546D01*
Y107409D01*
Y107272D01*
Y107135D01*
Y106997D01*
Y106860D01*
Y106722D01*
Y106585D01*
Y106448D01*
Y106311D01*
Y106173D01*
Y106036D01*
Y105899D01*
Y105761D01*
Y105624D01*
Y105487D01*
Y105349D01*
Y105212D01*
Y105075D01*
Y104937D01*
Y104800D01*
Y104663D01*
Y104525D01*
Y104388D01*
Y104251D01*
Y104114D01*
Y103976D01*
Y103839D01*
Y103701D01*
Y103564D01*
Y103427D01*
Y103290D01*
Y103152D01*
Y103015D01*
Y102878D01*
Y102740D01*
Y102603D01*
Y102466D01*
Y102328D01*
Y102191D01*
Y102054D01*
Y101916D01*
Y101779D01*
Y101642D01*
Y101504D01*
Y101367D01*
Y101230D01*
Y101093D01*
Y100955D01*
Y100818D01*
Y100681D01*
Y100543D01*
Y100406D01*
Y100269D01*
Y100131D01*
Y99994D01*
Y99857D01*
Y99719D01*
Y99582D01*
Y99445D01*
Y99307D01*
Y99170D01*
Y99033D01*
Y98895D01*
Y98758D01*
Y98621D01*
Y98483D01*
Y98346D01*
Y98209D01*
Y98071D01*
Y97934D01*
Y97797D01*
Y97660D01*
Y97522D01*
Y97385D01*
Y97248D01*
Y97110D01*
Y96973D01*
Y96836D01*
Y96698D01*
Y96561D01*
Y96424D01*
Y96286D01*
Y96149D01*
Y96012D01*
Y95875D01*
Y95737D01*
Y95600D01*
Y95463D01*
Y95325D01*
Y95188D01*
Y95051D01*
Y94913D01*
Y94776D01*
Y94639D01*
Y94501D01*
Y94364D01*
Y94227D01*
Y94089D01*
Y93952D01*
Y93815D01*
Y93677D01*
Y93540D01*
Y93403D01*
Y93265D01*
Y93128D01*
Y92991D01*
Y92853D01*
Y92716D01*
Y92579D01*
Y92442D01*
Y92304D01*
Y92167D01*
Y92030D01*
Y91892D01*
Y91755D01*
Y91618D01*
Y91480D01*
Y91343D01*
Y91206D01*
Y91068D01*
Y90931D01*
Y90794D01*
Y90656D01*
Y90519D01*
Y90382D01*
Y90244D01*
Y90107D01*
Y89970D01*
Y89832D01*
Y89695D01*
Y89558D01*
Y89420D01*
Y89283D01*
Y89146D01*
Y89009D01*
Y88871D01*
Y88734D01*
Y88597D01*
Y88459D01*
Y88322D01*
Y88185D01*
Y88047D01*
Y87910D01*
Y87773D01*
Y87635D01*
Y87498D01*
Y87361D01*
Y87223D01*
Y87086D01*
Y86949D01*
Y86812D01*
Y86674D01*
Y86537D01*
Y86399D01*
Y86262D01*
Y86125D01*
Y85988D01*
Y85850D01*
Y85713D01*
Y85576D01*
Y85438D01*
Y85301D01*
Y85164D01*
Y85026D01*
Y84889D01*
Y84752D01*
Y84614D01*
Y84477D01*
Y84340D01*
Y84202D01*
Y84065D01*
Y83928D01*
Y83791D01*
Y83653D01*
Y83516D01*
Y83379D01*
Y83241D01*
Y83104D01*
Y82967D01*
Y82829D01*
Y82692D01*
Y82555D01*
Y82417D01*
Y82280D01*
Y82143D01*
Y82005D01*
Y81868D01*
Y81731D01*
Y81593D01*
Y81456D01*
Y81319D01*
Y81181D01*
Y81044D01*
Y80907D01*
Y80770D01*
Y80632D01*
Y80495D01*
Y80358D01*
Y80220D01*
Y80083D01*
Y79946D01*
Y79808D01*
Y79671D01*
Y79534D01*
Y79396D01*
Y79259D01*
Y79122D01*
Y78984D01*
Y78847D01*
Y78710D01*
Y78573D01*
Y78435D01*
Y78298D01*
Y78161D01*
Y78023D01*
Y77886D01*
Y77748D01*
Y77611D01*
Y77474D01*
Y77337D01*
Y77199D01*
Y77062D01*
Y76925D01*
Y76787D01*
Y76650D01*
Y76513D01*
Y76375D01*
Y76238D01*
Y76101D01*
Y75963D01*
Y75826D01*
Y75689D01*
Y75552D01*
Y75414D01*
Y75277D01*
Y75139D01*
Y75002D01*
Y74865D01*
Y74728D01*
Y74590D01*
Y74453D01*
Y74316D01*
Y74178D01*
Y74041D01*
Y73904D01*
Y73766D01*
Y73629D01*
Y73492D01*
Y73354D01*
Y73217D01*
Y73080D01*
Y72942D01*
Y72805D01*
Y72668D01*
Y72530D01*
Y72393D01*
Y72256D01*
Y72119D01*
Y71981D01*
Y71844D01*
Y71707D01*
Y71569D01*
Y71432D01*
Y71295D01*
Y71157D01*
Y71020D01*
Y70883D01*
Y70745D01*
Y70608D01*
Y70471D01*
Y70333D01*
Y70196D01*
Y70059D01*
Y69921D01*
Y69784D01*
Y69647D01*
Y69510D01*
Y69372D01*
Y69235D01*
Y69098D01*
Y68960D01*
Y68823D01*
Y68686D01*
Y68548D01*
Y68411D01*
Y68274D01*
Y68136D01*
Y67999D01*
Y67862D01*
Y67724D01*
Y67587D01*
Y67450D01*
Y67312D01*
Y67175D01*
Y67038D01*
Y66901D01*
Y66763D01*
Y66626D01*
Y66488D01*
Y66351D01*
Y66214D01*
Y66077D01*
Y65939D01*
Y65802D01*
Y65665D01*
Y65527D01*
Y65390D01*
Y65253D01*
Y65115D01*
Y64978D01*
Y64841D01*
Y64703D01*
Y64566D01*
Y64429D01*
Y64291D01*
Y64154D01*
Y64017D01*
Y63879D01*
Y63742D01*
Y63605D01*
Y63467D01*
Y63330D01*
Y63193D01*
Y63056D01*
Y62918D01*
Y62781D01*
Y62644D01*
Y62506D01*
Y62369D01*
Y62232D01*
Y62094D01*
Y61957D01*
Y61820D01*
X436416D01*
Y61957D01*
Y62094D01*
Y62232D01*
Y62369D01*
Y62506D01*
Y62644D01*
Y62781D01*
Y62918D01*
Y63056D01*
Y63193D01*
Y63330D01*
Y63467D01*
Y63605D01*
Y63742D01*
Y63879D01*
Y64017D01*
Y64154D01*
Y64291D01*
Y64429D01*
Y64566D01*
Y64703D01*
Y64841D01*
Y64978D01*
Y65115D01*
Y65253D01*
Y65390D01*
Y65527D01*
Y65665D01*
Y65802D01*
Y65939D01*
Y66077D01*
Y66214D01*
Y66351D01*
Y66488D01*
Y66626D01*
Y66763D01*
Y66901D01*
Y67038D01*
Y67175D01*
Y67312D01*
Y67450D01*
Y67587D01*
Y67724D01*
Y67862D01*
Y67999D01*
Y68136D01*
Y68274D01*
Y68411D01*
Y68548D01*
Y68686D01*
Y68823D01*
Y68960D01*
Y69098D01*
Y69235D01*
Y69372D01*
Y69510D01*
Y69647D01*
Y69784D01*
Y69921D01*
Y70059D01*
Y70196D01*
Y70333D01*
Y70471D01*
Y70608D01*
Y70745D01*
Y70883D01*
Y71020D01*
Y71157D01*
Y71295D01*
Y71432D01*
Y71569D01*
Y71707D01*
Y71844D01*
Y71981D01*
Y72119D01*
Y72256D01*
Y72393D01*
Y72530D01*
Y72668D01*
Y72805D01*
Y72942D01*
Y73080D01*
Y73217D01*
Y73354D01*
Y73492D01*
Y73629D01*
Y73766D01*
Y73904D01*
Y74041D01*
Y74178D01*
Y74316D01*
Y74453D01*
Y74590D01*
Y74728D01*
Y74865D01*
Y75002D01*
Y75139D01*
Y75277D01*
Y75414D01*
Y75552D01*
Y75689D01*
Y75826D01*
Y75963D01*
Y76101D01*
Y76238D01*
Y76375D01*
Y76513D01*
Y76650D01*
Y76787D01*
Y76925D01*
Y77062D01*
Y77199D01*
Y77337D01*
Y77474D01*
Y77611D01*
Y77748D01*
Y77886D01*
Y78023D01*
Y78161D01*
Y78298D01*
Y78435D01*
Y78573D01*
Y78710D01*
Y78847D01*
Y78984D01*
Y79122D01*
Y79259D01*
Y79396D01*
Y79534D01*
Y79671D01*
Y79808D01*
Y79946D01*
Y80083D01*
Y80220D01*
Y80358D01*
Y80495D01*
Y80632D01*
Y80770D01*
Y80907D01*
Y81044D01*
Y81181D01*
Y81319D01*
Y81456D01*
Y81593D01*
Y81731D01*
Y81868D01*
Y82005D01*
Y82143D01*
Y82280D01*
Y82417D01*
Y82555D01*
Y82692D01*
Y82829D01*
Y82967D01*
Y83104D01*
Y83241D01*
Y83379D01*
Y83516D01*
Y83653D01*
Y83791D01*
Y83928D01*
Y84065D01*
Y84202D01*
Y84340D01*
Y84477D01*
Y84614D01*
Y84752D01*
Y84889D01*
Y85026D01*
Y85164D01*
Y85301D01*
Y85438D01*
Y85576D01*
Y85713D01*
Y85850D01*
Y85988D01*
Y86125D01*
Y86262D01*
Y86399D01*
Y86537D01*
Y86674D01*
Y86812D01*
Y86949D01*
Y87086D01*
Y87223D01*
Y87361D01*
Y87498D01*
Y87635D01*
Y87773D01*
Y87910D01*
Y88047D01*
Y88185D01*
Y88322D01*
Y88459D01*
Y88597D01*
Y88734D01*
Y88871D01*
Y89009D01*
Y89146D01*
Y89283D01*
Y89420D01*
Y89558D01*
Y89695D01*
Y89832D01*
Y89970D01*
Y90107D01*
Y90244D01*
Y90382D01*
Y90519D01*
Y90656D01*
Y90794D01*
Y90931D01*
Y91068D01*
Y91206D01*
Y91343D01*
Y91480D01*
Y91618D01*
Y91755D01*
Y91892D01*
Y92030D01*
Y92167D01*
Y92304D01*
Y92442D01*
Y92579D01*
Y92716D01*
Y92853D01*
Y92991D01*
Y93128D01*
Y93265D01*
Y93403D01*
Y93540D01*
Y93677D01*
Y93815D01*
Y93952D01*
Y94089D01*
Y94227D01*
Y94364D01*
Y94501D01*
Y94639D01*
Y94776D01*
Y94913D01*
Y95051D01*
Y95188D01*
Y95325D01*
Y95463D01*
Y95600D01*
Y95737D01*
Y95875D01*
Y96012D01*
Y96149D01*
Y96286D01*
Y96424D01*
Y96561D01*
Y96698D01*
Y96836D01*
Y96973D01*
Y97110D01*
Y97248D01*
Y97385D01*
Y97522D01*
Y97660D01*
Y97797D01*
Y97934D01*
Y98071D01*
Y98209D01*
Y98346D01*
Y98483D01*
Y98621D01*
Y98758D01*
Y98895D01*
Y99033D01*
Y99170D01*
Y99307D01*
Y99445D01*
Y99582D01*
Y99719D01*
Y99857D01*
Y99994D01*
Y100131D01*
Y100269D01*
Y100406D01*
Y100543D01*
Y100681D01*
Y100818D01*
Y100955D01*
Y101093D01*
Y101230D01*
Y101367D01*
Y101504D01*
Y101642D01*
Y101779D01*
Y101916D01*
Y102054D01*
Y102191D01*
Y102328D01*
Y102466D01*
Y102603D01*
Y102740D01*
Y102878D01*
Y103015D01*
Y103152D01*
Y103290D01*
Y103427D01*
Y103564D01*
Y103701D01*
Y103839D01*
Y103976D01*
Y104114D01*
Y104251D01*
Y104388D01*
Y104525D01*
Y104663D01*
Y104800D01*
Y104937D01*
Y105075D01*
Y105212D01*
Y105349D01*
Y105487D01*
Y105624D01*
Y105761D01*
Y105899D01*
Y106036D01*
Y106173D01*
Y106311D01*
Y106448D01*
Y106585D01*
Y106722D01*
Y106860D01*
Y106997D01*
Y107135D01*
Y107272D01*
Y107409D01*
Y107546D01*
Y107684D01*
Y107821D01*
Y107958D01*
Y108096D01*
Y108233D01*
Y108370D01*
Y108508D01*
Y108645D01*
Y108782D01*
Y108920D01*
Y109057D01*
Y109194D01*
Y109332D01*
Y109469D01*
Y109606D01*
Y109743D01*
Y109881D01*
Y110018D01*
Y110155D01*
Y110293D01*
Y110430D01*
Y110567D01*
Y110705D01*
Y110842D01*
Y110979D01*
Y111117D01*
Y111254D01*
Y111391D01*
Y111529D01*
Y111666D01*
Y111803D01*
Y111941D01*
Y112078D01*
Y112215D01*
Y112353D01*
Y112490D01*
Y112627D01*
Y112765D01*
Y112902D01*
Y113039D01*
Y113176D01*
Y113314D01*
Y113451D01*
Y113588D01*
Y113726D01*
Y113863D01*
Y114000D01*
Y114138D01*
Y114275D01*
Y114412D01*
Y114550D01*
Y114687D01*
Y114824D01*
Y114962D01*
Y115099D01*
Y115236D01*
Y115373D01*
Y115511D01*
Y115648D01*
Y115786D01*
Y115923D01*
Y116060D01*
Y116198D01*
Y116335D01*
Y116472D01*
Y116609D01*
Y116747D01*
Y116884D01*
Y117021D01*
Y117159D01*
Y117296D01*
Y117433D01*
Y117571D01*
Y117708D01*
Y117845D01*
Y117983D01*
Y118120D01*
Y118257D01*
Y118394D01*
Y118532D01*
Y118669D01*
Y118806D01*
Y118944D01*
Y119081D01*
Y119218D01*
Y119356D01*
Y119493D01*
Y119630D01*
Y119768D01*
Y119905D01*
Y120042D01*
Y120180D01*
Y120317D01*
Y120454D01*
Y120592D01*
Y120729D01*
Y120866D01*
Y121004D01*
Y121141D01*
Y121278D01*
Y121416D01*
Y121553D01*
Y121690D01*
Y121827D01*
Y121965D01*
Y122102D01*
Y122239D01*
Y122377D01*
Y122514D01*
Y122651D01*
Y122789D01*
Y122926D01*
Y123063D01*
Y123201D01*
Y123338D01*
Y123475D01*
Y123613D01*
Y123750D01*
Y123887D01*
Y124024D01*
Y124162D01*
Y124299D01*
Y124437D01*
Y124574D01*
Y124711D01*
Y124848D01*
Y124986D01*
Y125123D01*
Y125260D01*
Y125398D01*
Y125535D01*
Y125672D01*
Y125810D01*
Y125947D01*
Y126084D01*
Y126222D01*
Y126359D01*
Y126496D01*
Y126634D01*
Y126771D01*
Y126908D01*
Y127045D01*
Y127183D01*
Y127320D01*
Y127458D01*
Y127595D01*
Y127732D01*
Y127869D01*
Y128007D01*
Y128144D01*
Y128281D01*
Y128419D01*
Y128556D01*
Y128693D01*
Y128831D01*
Y128968D01*
Y129105D01*
Y129243D01*
Y129380D01*
Y129517D01*
Y129655D01*
Y129792D01*
Y129929D01*
Y130066D01*
Y130204D01*
Y130341D01*
Y130478D01*
Y130616D01*
Y130753D01*
Y130890D01*
Y131028D01*
Y131165D01*
Y131302D01*
Y131440D01*
Y131577D01*
Y131714D01*
Y131852D01*
Y131989D01*
Y132126D01*
Y132264D01*
Y132401D01*
Y132538D01*
Y132676D01*
Y132813D01*
Y132950D01*
Y133088D01*
Y133225D01*
Y133362D01*
Y133499D01*
Y133637D01*
Y133774D01*
Y133911D01*
Y134049D01*
Y134186D01*
Y134323D01*
Y134461D01*
Y134598D01*
Y134735D01*
Y134873D01*
Y135010D01*
Y135147D01*
Y135285D01*
Y135422D01*
Y135559D01*
Y135696D01*
Y135834D01*
Y135971D01*
Y136109D01*
Y136246D01*
Y136383D01*
Y136520D01*
Y136658D01*
Y136795D01*
Y136932D01*
Y137070D01*
Y137207D01*
Y137344D01*
Y137482D01*
Y137619D01*
Y137756D01*
Y137894D01*
Y138031D01*
Y138168D01*
Y138306D01*
Y138443D01*
Y138580D01*
Y138717D01*
Y138855D01*
Y138992D01*
Y139129D01*
Y139267D01*
Y139404D01*
Y139541D01*
Y139679D01*
Y139816D01*
Y139953D01*
Y140091D01*
Y140228D01*
Y140365D01*
Y140503D01*
Y140640D01*
Y140777D01*
Y140915D01*
Y141052D01*
Y141189D01*
Y141327D01*
Y141464D01*
Y141601D01*
Y141739D01*
Y141876D01*
Y142013D01*
Y142150D01*
Y142288D01*
Y142425D01*
Y142562D01*
Y142700D01*
Y142837D01*
Y142974D01*
Y143112D01*
Y143249D01*
Y143386D01*
Y143524D01*
Y143661D01*
Y143798D01*
Y143936D01*
Y144073D01*
Y144210D01*
Y144347D01*
Y144485D01*
Y144622D01*
Y144760D01*
Y144897D01*
Y145034D01*
Y145171D01*
Y145309D01*
Y145446D01*
Y145583D01*
Y145721D01*
Y145858D01*
Y145995D01*
Y146133D01*
Y146270D01*
Y146407D01*
Y146545D01*
Y146682D01*
Y146819D01*
Y146957D01*
Y147094D01*
Y147231D01*
Y147368D01*
Y147506D01*
Y147643D01*
Y147781D01*
Y147918D01*
Y148055D01*
Y148192D01*
Y148330D01*
Y148467D01*
Y148604D01*
Y148742D01*
Y148879D01*
Y149016D01*
Y149154D01*
Y149291D01*
Y149428D01*
Y149566D01*
Y149703D01*
Y149840D01*
Y149978D01*
Y150115D01*
Y150252D01*
Y150389D01*
Y150527D01*
Y150664D01*
Y150801D01*
Y150939D01*
Y151076D01*
Y151213D01*
Y151351D01*
Y151488D01*
Y151625D01*
Y151763D01*
Y151900D01*
Y152037D01*
Y152175D01*
Y152312D01*
Y152449D01*
Y152587D01*
Y152724D01*
Y152861D01*
Y152999D01*
Y153136D01*
Y153273D01*
Y153411D01*
Y153548D01*
Y153685D01*
Y153822D01*
Y153960D01*
Y154097D01*
Y154234D01*
Y154372D01*
Y154509D01*
Y154646D01*
Y154784D01*
Y154921D01*
Y155058D01*
Y155196D01*
Y155333D01*
Y155470D01*
Y155608D01*
Y155745D01*
Y155882D01*
Y156019D01*
Y156157D01*
Y156294D01*
Y156432D01*
Y156569D01*
Y156706D01*
Y156843D01*
Y156981D01*
Y157118D01*
Y157255D01*
Y157393D01*
Y157530D01*
Y157667D01*
Y157805D01*
Y157942D01*
Y158079D01*
Y158217D01*
Y158354D01*
Y158491D01*
Y158629D01*
Y158766D01*
Y158903D01*
Y159040D01*
Y159178D01*
Y159315D01*
Y159452D01*
Y159590D01*
Y159727D01*
Y159864D01*
Y160002D01*
Y160139D01*
Y160276D01*
Y160414D01*
Y160551D01*
Y160688D01*
Y160826D01*
Y160963D01*
Y161100D01*
Y161238D01*
Y161375D01*
Y161512D01*
Y161649D01*
Y161787D01*
Y161924D01*
Y162062D01*
Y162199D01*
Y162336D01*
Y162473D01*
Y162611D01*
Y162748D01*
Y162885D01*
Y163023D01*
Y163160D01*
Y163297D01*
Y163435D01*
Y163572D01*
Y163709D01*
Y163847D01*
Y163984D01*
Y164121D01*
Y164259D01*
Y164396D01*
Y164533D01*
Y164671D01*
Y164808D01*
Y164945D01*
Y165082D01*
Y165220D01*
Y165357D01*
Y165494D01*
Y165632D01*
Y165769D01*
Y165906D01*
Y166044D01*
Y166181D01*
Y166318D01*
Y166456D01*
Y166593D01*
Y166730D01*
Y166868D01*
Y167005D01*
Y167142D01*
Y167280D01*
Y167417D01*
Y167554D01*
Y167691D01*
Y167829D01*
Y167966D01*
Y168104D01*
Y168241D01*
Y168378D01*
Y168515D01*
Y168653D01*
Y168790D01*
Y168927D01*
Y169065D01*
Y169202D01*
Y169339D01*
Y169477D01*
Y169614D01*
Y169751D01*
Y169889D01*
Y170026D01*
Y170163D01*
Y170301D01*
Y170438D01*
Y170575D01*
Y170713D01*
Y170850D01*
Y170987D01*
Y171124D01*
Y171262D01*
Y171399D01*
Y171536D01*
Y171674D01*
Y171811D01*
Y171948D01*
Y172086D01*
Y172223D01*
Y172360D01*
Y172498D01*
Y172635D01*
Y172772D01*
Y172910D01*
Y173047D01*
Y173184D01*
Y173321D01*
Y173459D01*
Y173596D01*
Y173734D01*
Y173871D01*
Y174008D01*
Y174145D01*
Y174283D01*
Y174420D01*
Y174557D01*
Y174695D01*
Y174832D01*
Y174969D01*
Y175107D01*
Y175244D01*
Y175381D01*
Y175519D01*
Y175656D01*
Y175793D01*
Y175931D01*
Y176068D01*
Y176205D01*
Y176343D01*
Y176480D01*
Y176617D01*
Y176754D01*
Y176892D01*
Y177029D01*
Y177166D01*
Y177304D01*
Y177441D01*
Y177578D01*
Y177716D01*
Y177853D01*
Y177990D01*
Y178128D01*
Y178265D01*
Y178402D01*
Y178540D01*
Y178677D01*
Y178814D01*
Y178952D01*
Y179089D01*
Y179226D01*
Y179363D01*
Y179501D01*
Y179638D01*
Y179776D01*
Y179913D01*
Y180050D01*
Y180187D01*
Y180325D01*
Y180462D01*
Y180599D01*
Y180737D01*
Y180874D01*
Y181011D01*
Y181149D01*
Y181286D01*
Y181423D01*
Y181561D01*
Y181698D01*
Y181835D01*
Y181973D01*
Y182110D01*
Y182247D01*
Y182384D01*
Y182522D01*
Y182659D01*
Y182796D01*
Y182934D01*
Y183071D01*
Y183208D01*
Y183346D01*
Y183483D01*
Y183620D01*
Y183758D01*
Y183895D01*
Y184032D01*
Y184170D01*
Y184307D01*
Y184444D01*
Y184582D01*
Y184719D01*
Y184856D01*
Y184993D01*
Y185131D01*
Y185268D01*
Y185406D01*
Y185543D01*
Y185680D01*
Y185817D01*
Y185955D01*
Y186092D01*
Y186229D01*
Y186367D01*
Y186504D01*
Y186641D01*
Y186779D01*
Y186916D01*
Y187053D01*
Y187191D01*
Y187328D01*
Y187465D01*
Y187603D01*
Y187740D01*
Y187877D01*
Y188015D01*
Y188152D01*
Y188289D01*
Y188426D01*
Y188564D01*
Y188701D01*
Y188838D01*
Y188976D01*
Y189113D01*
Y189250D01*
Y189388D01*
Y189525D01*
Y189662D01*
Y189800D01*
Y189937D01*
Y190074D01*
Y190212D01*
Y190349D01*
Y190486D01*
Y190623D01*
Y190761D01*
Y190898D01*
Y191035D01*
Y191173D01*
Y191310D01*
Y191447D01*
Y191585D01*
Y191722D01*
Y191859D01*
Y191997D01*
Y192134D01*
Y192271D01*
Y192409D01*
Y192546D01*
Y192683D01*
Y192821D01*
Y192958D01*
Y193095D01*
Y193233D01*
Y193370D01*
Y193507D01*
Y193645D01*
Y193782D01*
Y193919D01*
Y194056D01*
Y194194D01*
Y194331D01*
Y194468D01*
Y194606D01*
Y194743D01*
Y194880D01*
Y195018D01*
Y195155D01*
Y195292D01*
Y195430D01*
Y195567D01*
Y195704D01*
Y195842D01*
Y195979D01*
Y196116D01*
Y196254D01*
Y196391D01*
Y196528D01*
Y196665D01*
Y196803D01*
Y196940D01*
Y197078D01*
Y197215D01*
Y197352D01*
Y197489D01*
Y197627D01*
Y197764D01*
Y197901D01*
Y198039D01*
Y198176D01*
Y198313D01*
Y198451D01*
Y198588D01*
Y198725D01*
Y198863D01*
Y199000D01*
Y199137D01*
Y199275D01*
Y199412D01*
Y199549D01*
Y199687D01*
Y199824D01*
Y199961D01*
Y200098D01*
Y200236D01*
Y200373D01*
Y200510D01*
Y200648D01*
Y200785D01*
Y200922D01*
Y201060D01*
Y201197D01*
Y201334D01*
Y201472D01*
Y201609D01*
Y201746D01*
Y201884D01*
Y202021D01*
Y202158D01*
Y202295D01*
Y202433D01*
Y202570D01*
Y202708D01*
Y202845D01*
Y202982D01*
Y203119D01*
Y203257D01*
Y203394D01*
Y203531D01*
Y203669D01*
Y203806D01*
Y203943D01*
Y204081D01*
Y204218D01*
Y204355D01*
Y204493D01*
Y204630D01*
Y204767D01*
Y204905D01*
Y205042D01*
Y205179D01*
Y205317D01*
Y205454D01*
Y205591D01*
Y205728D01*
Y205866D01*
Y206003D01*
Y206140D01*
Y206278D01*
Y206415D01*
Y206552D01*
Y206690D01*
Y206827D01*
Y206964D01*
Y207102D01*
Y207239D01*
Y207376D01*
Y207514D01*
Y207651D01*
Y207788D01*
Y207925D01*
Y208063D01*
Y208200D01*
Y208337D01*
Y208475D01*
Y208612D01*
Y208749D01*
Y208887D01*
Y209024D01*
Y209161D01*
Y209299D01*
Y209436D01*
Y209573D01*
Y209711D01*
Y209848D01*
Y209985D01*
Y210123D01*
Y210260D01*
Y210397D01*
Y210535D01*
Y210672D01*
Y210809D01*
Y210947D01*
Y211084D01*
Y211221D01*
Y211359D01*
Y211496D01*
Y211633D01*
Y211770D01*
X436553D01*
Y211908D01*
Y212045D01*
Y212182D01*
Y212320D01*
Y212457D01*
X436690D01*
Y212594D01*
Y212732D01*
Y212869D01*
Y213006D01*
X436828D01*
Y213144D01*
Y213281D01*
X436965D01*
Y213418D01*
Y213556D01*
Y213693D01*
X437102D01*
Y213830D01*
Y213967D01*
X437240D01*
Y214105D01*
Y214242D01*
X437377D01*
Y214380D01*
Y214517D01*
X437514D01*
Y214654D01*
Y214791D01*
X437652D01*
Y214929D01*
X437789D01*
Y215066D01*
Y215203D01*
X437926D01*
Y215341D01*
X438064D01*
Y215478D01*
X438201D01*
Y215615D01*
Y215753D01*
X438338D01*
Y215890D01*
X438476D01*
Y216027D01*
X438613D01*
Y216165D01*
X438750D01*
Y216302D01*
X438887D01*
Y216439D01*
X439025D01*
Y216577D01*
X439162D01*
Y216714D01*
X439300D01*
Y216851D01*
X439574D01*
Y216989D01*
X439711D01*
Y217126D01*
X439849D01*
Y217263D01*
X440123D01*
Y217400D01*
X440261D01*
Y217538D01*
X440535D01*
Y217675D01*
X440810D01*
Y217812D01*
X441085D01*
Y217950D01*
X441359D01*
Y218087D01*
X441771D01*
Y218224D01*
X442046D01*
Y218362D01*
X442595D01*
Y218499D01*
X443144D01*
Y218636D01*
X444518D01*
Y218774D01*
X461957D01*
Y218636D01*
D02*
G37*
G36*
X327881Y32614D02*
X326677D01*
Y33975D01*
X327881D01*
Y32614D01*
D02*
G37*
G36*
X379506Y31434D02*
X379747Y31398D01*
X379952Y31338D01*
X380145Y31290D01*
X380289Y31230D01*
X380409Y31170D01*
X380482Y31133D01*
X380494Y31121D01*
X380506D01*
X380698Y31001D01*
X380879Y30856D01*
X381035Y30724D01*
X381156Y30592D01*
X381264Y30471D01*
X381337Y30375D01*
X381385Y30315D01*
X381397Y30303D01*
Y31290D01*
X382468D01*
Y24211D01*
X381264D01*
Y27883D01*
X381252Y28220D01*
X381228Y28521D01*
X381204Y28774D01*
X381168Y28978D01*
X381132Y29147D01*
X381096Y29255D01*
X381084Y29327D01*
X381072Y29351D01*
X380987Y29532D01*
X380891Y29689D01*
X380795Y29821D01*
X380686Y29941D01*
X380602Y30026D01*
X380530Y30086D01*
X380482Y30122D01*
X380458Y30134D01*
X380289Y30230D01*
X380132Y30291D01*
X379964Y30339D01*
X379819Y30375D01*
X379699Y30399D01*
X379603Y30411D01*
X379519D01*
X379278Y30399D01*
X379085Y30351D01*
X378917Y30278D01*
X378784Y30206D01*
X378688Y30134D01*
X378615Y30062D01*
X378567Y30014D01*
X378555Y30002D01*
X378459Y29833D01*
X378387Y29653D01*
X378339Y29448D01*
X378302Y29255D01*
X378278Y29087D01*
X378266Y28942D01*
Y28882D01*
Y28846D01*
Y28822D01*
Y28810D01*
Y24211D01*
X377062D01*
Y28316D01*
Y28521D01*
X377038Y28701D01*
X377014Y28870D01*
X376990Y29026D01*
X376942Y29171D01*
X376906Y29303D01*
X376858Y29424D01*
X376810Y29520D01*
X376773Y29616D01*
X376725Y29689D01*
X376677Y29761D01*
X376641Y29809D01*
X376617Y29857D01*
X376593Y29881D01*
X376569Y29905D01*
X376376Y30074D01*
X376171Y30194D01*
X375955Y30291D01*
X375762Y30351D01*
X375594Y30387D01*
X375449Y30399D01*
X375401Y30411D01*
X375329D01*
X375172Y30399D01*
X375040Y30375D01*
X374919Y30351D01*
X374811Y30315D01*
X374727Y30266D01*
X374655Y30242D01*
X374618Y30218D01*
X374606Y30206D01*
X374498Y30134D01*
X374414Y30050D01*
X374329Y29966D01*
X374281Y29881D01*
X374233Y29809D01*
X374209Y29749D01*
X374185Y29713D01*
Y29701D01*
X374149Y29568D01*
X374113Y29412D01*
X374089Y29231D01*
X374077Y29062D01*
X374065Y28906D01*
Y28786D01*
Y28737D01*
Y28701D01*
Y28677D01*
Y28665D01*
Y24211D01*
X372861D01*
Y29062D01*
Y29279D01*
X372885Y29484D01*
X372909Y29676D01*
X372945Y29857D01*
X372993Y30014D01*
X373041Y30170D01*
X373089Y30303D01*
X373138Y30411D01*
X373198Y30519D01*
X373246Y30616D01*
X373294Y30688D01*
X373342Y30748D01*
X373378Y30796D01*
X373402Y30832D01*
X373414Y30844D01*
X373427Y30856D01*
X373535Y30965D01*
X373655Y31049D01*
X373788Y31133D01*
X373920Y31193D01*
X374185Y31302D01*
X374450Y31374D01*
X374691Y31410D01*
X374787Y31434D01*
X374871D01*
X374955Y31446D01*
X375052D01*
X375293Y31434D01*
X375533Y31398D01*
X375750Y31338D01*
X375967Y31254D01*
X376159Y31157D01*
X376340Y31049D01*
X376509Y30941D01*
X376653Y30832D01*
X376786Y30712D01*
X376906Y30604D01*
X377002Y30495D01*
X377086Y30399D01*
X377159Y30327D01*
X377207Y30254D01*
X377231Y30218D01*
X377243Y30206D01*
X377339Y30411D01*
X377448Y30592D01*
X377568Y30748D01*
X377688Y30880D01*
X377797Y30977D01*
X377881Y31049D01*
X377941Y31097D01*
X377965Y31109D01*
X378158Y31218D01*
X378375Y31302D01*
X378591Y31362D01*
X378796Y31410D01*
X378977Y31434D01*
X379049D01*
X379121Y31446D01*
X379254D01*
X379506Y31434D01*
D02*
G37*
G36*
X368454D02*
X368755Y31410D01*
X369032Y31362D01*
X369261Y31326D01*
X369369Y31302D01*
X369465Y31278D01*
X369538Y31254D01*
X369610Y31230D01*
X369658Y31218D01*
X369694Y31206D01*
X369718Y31193D01*
X369730D01*
X369971Y31085D01*
X370188Y30977D01*
X370368Y30856D01*
X370513Y30736D01*
X370633Y30628D01*
X370718Y30543D01*
X370778Y30495D01*
X370790Y30471D01*
X370910Y30291D01*
X371018Y30086D01*
X371115Y29893D01*
X371187Y29701D01*
X371235Y29532D01*
X371271Y29388D01*
X371295Y29339D01*
Y29303D01*
X371307Y29279D01*
Y29267D01*
X370140Y29111D01*
X370055Y29376D01*
X369971Y29592D01*
X369863Y29773D01*
X369766Y29917D01*
X369682Y30026D01*
X369610Y30098D01*
X369562Y30146D01*
X369550Y30158D01*
X369381Y30254D01*
X369176Y30327D01*
X368972Y30387D01*
X368767Y30423D01*
X368574Y30447D01*
X368490D01*
X368430Y30459D01*
X368285D01*
X367961Y30447D01*
X367684Y30399D01*
X367443Y30327D01*
X367250Y30254D01*
X367106Y30182D01*
X366997Y30110D01*
X366937Y30062D01*
X366913Y30050D01*
X366793Y29917D01*
X366708Y29761D01*
X366648Y29592D01*
X366612Y29424D01*
X366576Y29267D01*
X366564Y29135D01*
Y29087D01*
Y29051D01*
Y29026D01*
Y29014D01*
Y28978D01*
Y28930D01*
Y28834D01*
X366576Y28786D01*
Y28737D01*
Y28713D01*
Y28701D01*
X366708Y28653D01*
X366865Y28617D01*
X367202Y28533D01*
X367551Y28461D01*
X367900Y28400D01*
X368069Y28376D01*
X368225Y28352D01*
X368358Y28328D01*
X368478Y28316D01*
X368574Y28304D01*
X368659Y28292D01*
X368707Y28280D01*
X368719D01*
X368972Y28244D01*
X369188Y28220D01*
X369369Y28184D01*
X369526Y28160D01*
X369646Y28135D01*
X369718Y28111D01*
X369779Y28099D01*
X369790D01*
X369971Y28039D01*
X370128Y27979D01*
X370272Y27919D01*
X370405Y27847D01*
X370513Y27798D01*
X370585Y27750D01*
X370645Y27714D01*
X370657Y27702D01*
X370790Y27606D01*
X370922Y27485D01*
X371018Y27377D01*
X371115Y27269D01*
X371187Y27172D01*
X371235Y27088D01*
X371271Y27040D01*
X371283Y27016D01*
X371356Y26859D01*
X371416Y26691D01*
X371452Y26534D01*
X371488Y26390D01*
X371500Y26257D01*
X371512Y26161D01*
Y26101D01*
Y26089D01*
Y26077D01*
X371500Y25908D01*
X371488Y25764D01*
X371416Y25475D01*
X371320Y25222D01*
X371199Y25017D01*
X371079Y24849D01*
X370982Y24728D01*
X370946Y24680D01*
X370910Y24644D01*
X370898Y24632D01*
X370886Y24620D01*
X370766Y24524D01*
X370633Y24439D01*
X370344Y24295D01*
X370043Y24199D01*
X369754Y24126D01*
X369622Y24102D01*
X369490Y24090D01*
X369381Y24066D01*
X369285D01*
X369201Y24054D01*
X369092D01*
X368827Y24066D01*
X368587Y24090D01*
X368358Y24126D01*
X368165Y24174D01*
X367997Y24211D01*
X367876Y24247D01*
X367828Y24259D01*
X367792Y24271D01*
X367780Y24283D01*
X367768D01*
X367527Y24391D01*
X367298Y24512D01*
X367082Y24644D01*
X366877Y24788D01*
X366708Y24909D01*
X366588Y25005D01*
X366528Y25041D01*
X366492Y25077D01*
X366480Y25089D01*
X366468Y25101D01*
X366443Y24921D01*
X366407Y24740D01*
X366383Y24596D01*
X366335Y24463D01*
X366311Y24355D01*
X366275Y24283D01*
X366263Y24223D01*
X366251Y24211D01*
X364999D01*
X365071Y24367D01*
X365131Y24512D01*
X365179Y24656D01*
X365228Y24776D01*
X365252Y24897D01*
X365276Y24981D01*
X365288Y25029D01*
Y25053D01*
X365300Y25150D01*
X365312Y25270D01*
X365324Y25415D01*
Y25571D01*
X365348Y25920D01*
Y26281D01*
Y26450D01*
X365360Y26618D01*
Y26775D01*
Y26907D01*
Y27016D01*
Y27100D01*
Y27148D01*
Y27172D01*
Y28774D01*
Y29051D01*
X365372Y29279D01*
X365384Y29472D01*
Y29628D01*
X365396Y29737D01*
X365408Y29821D01*
X365420Y29869D01*
Y29881D01*
X365468Y30050D01*
X365528Y30206D01*
X365589Y30351D01*
X365649Y30471D01*
X365709Y30555D01*
X365757Y30628D01*
X365793Y30676D01*
X365805Y30688D01*
X365914Y30808D01*
X366046Y30905D01*
X366179Y31001D01*
X366323Y31085D01*
X366443Y31145D01*
X366540Y31193D01*
X366612Y31218D01*
X366624Y31230D01*
X366636D01*
X366865Y31302D01*
X367106Y31350D01*
X367359Y31398D01*
X367587Y31422D01*
X367792Y31434D01*
X367888D01*
X367961Y31446D01*
X368117D01*
X368454Y31434D01*
D02*
G37*
G36*
X314625D02*
X314926Y31410D01*
X315203Y31362D01*
X315432Y31326D01*
X315540Y31302D01*
X315636Y31278D01*
X315709Y31254D01*
X315781Y31230D01*
X315829Y31218D01*
X315865Y31206D01*
X315889Y31193D01*
X315901D01*
X316142Y31085D01*
X316359Y30977D01*
X316539Y30856D01*
X316684Y30736D01*
X316804Y30628D01*
X316889Y30543D01*
X316949Y30495D01*
X316961Y30471D01*
X317081Y30291D01*
X317190Y30086D01*
X317286Y29893D01*
X317358Y29701D01*
X317406Y29532D01*
X317442Y29388D01*
X317466Y29339D01*
Y29303D01*
X317478Y29279D01*
Y29267D01*
X316311Y29111D01*
X316226Y29376D01*
X316142Y29592D01*
X316034Y29773D01*
X315937Y29917D01*
X315853Y30026D01*
X315781Y30098D01*
X315733Y30146D01*
X315721Y30158D01*
X315552Y30254D01*
X315347Y30327D01*
X315143Y30387D01*
X314938Y30423D01*
X314745Y30447D01*
X314661D01*
X314601Y30459D01*
X314457D01*
X314131Y30447D01*
X313855Y30399D01*
X313614Y30327D01*
X313421Y30254D01*
X313277Y30182D01*
X313168Y30110D01*
X313108Y30062D01*
X313084Y30050D01*
X312964Y29917D01*
X312879Y29761D01*
X312819Y29592D01*
X312783Y29424D01*
X312747Y29267D01*
X312735Y29135D01*
Y29087D01*
Y29051D01*
Y29026D01*
Y29014D01*
Y28978D01*
Y28930D01*
Y28834D01*
X312747Y28786D01*
Y28737D01*
Y28713D01*
Y28701D01*
X312879Y28653D01*
X313036Y28617D01*
X313373Y28533D01*
X313722Y28461D01*
X314071Y28400D01*
X314240Y28376D01*
X314396Y28352D01*
X314529Y28328D01*
X314649Y28316D01*
X314745Y28304D01*
X314830Y28292D01*
X314878Y28280D01*
X314890D01*
X315143Y28244D01*
X315359Y28220D01*
X315540Y28184D01*
X315697Y28160D01*
X315817Y28135D01*
X315889Y28111D01*
X315949Y28099D01*
X315961D01*
X316142Y28039D01*
X316299Y27979D01*
X316443Y27919D01*
X316576Y27847D01*
X316684Y27798D01*
X316756Y27750D01*
X316816Y27714D01*
X316828Y27702D01*
X316961Y27606D01*
X317093Y27485D01*
X317190Y27377D01*
X317286Y27269D01*
X317358Y27172D01*
X317406Y27088D01*
X317442Y27040D01*
X317454Y27016D01*
X317527Y26859D01*
X317587Y26691D01*
X317623Y26534D01*
X317659Y26390D01*
X317671Y26257D01*
X317683Y26161D01*
Y26101D01*
Y26089D01*
Y26077D01*
X317671Y25908D01*
X317659Y25764D01*
X317587Y25475D01*
X317491Y25222D01*
X317370Y25017D01*
X317250Y24849D01*
X317153Y24728D01*
X317117Y24680D01*
X317081Y24644D01*
X317069Y24632D01*
X317057Y24620D01*
X316937Y24524D01*
X316804Y24439D01*
X316515Y24295D01*
X316214Y24199D01*
X315925Y24126D01*
X315793Y24102D01*
X315660Y24090D01*
X315552Y24066D01*
X315456D01*
X315371Y24054D01*
X315263D01*
X314998Y24066D01*
X314757Y24090D01*
X314529Y24126D01*
X314336Y24174D01*
X314167Y24211D01*
X314047Y24247D01*
X313999Y24259D01*
X313963Y24271D01*
X313951Y24283D01*
X313939D01*
X313698Y24391D01*
X313469Y24512D01*
X313253Y24644D01*
X313048Y24788D01*
X312879Y24909D01*
X312759Y25005D01*
X312699Y25041D01*
X312663Y25077D01*
X312651Y25089D01*
X312638Y25101D01*
X312614Y24921D01*
X312578Y24740D01*
X312554Y24596D01*
X312506Y24463D01*
X312482Y24355D01*
X312446Y24283D01*
X312434Y24223D01*
X312422Y24211D01*
X311170D01*
X311242Y24367D01*
X311302Y24512D01*
X311350Y24656D01*
X311398Y24776D01*
X311423Y24897D01*
X311447Y24981D01*
X311459Y25029D01*
Y25053D01*
X311471Y25150D01*
X311483Y25270D01*
X311495Y25415D01*
Y25571D01*
X311519Y25920D01*
Y26281D01*
Y26450D01*
X311531Y26618D01*
Y26775D01*
Y26907D01*
Y27016D01*
Y27100D01*
Y27148D01*
Y27172D01*
Y28774D01*
Y29051D01*
X311543Y29279D01*
X311555Y29472D01*
Y29628D01*
X311567Y29737D01*
X311579Y29821D01*
X311591Y29869D01*
Y29881D01*
X311639Y30050D01*
X311699Y30206D01*
X311760Y30351D01*
X311820Y30471D01*
X311880Y30555D01*
X311928Y30628D01*
X311964Y30676D01*
X311976Y30688D01*
X312085Y30808D01*
X312217Y30905D01*
X312350Y31001D01*
X312494Y31085D01*
X312614Y31145D01*
X312711Y31193D01*
X312783Y31218D01*
X312795Y31230D01*
X312807D01*
X313036Y31302D01*
X313277Y31350D01*
X313529Y31398D01*
X313758Y31422D01*
X313963Y31434D01*
X314059D01*
X314131Y31446D01*
X314288D01*
X314625Y31434D01*
D02*
G37*
G36*
X304042D02*
X304307Y31410D01*
X304548Y31350D01*
X304765Y31290D01*
X304981Y31218D01*
X305174Y31133D01*
X305355Y31049D01*
X305523Y30953D01*
X305668Y30856D01*
X305788Y30772D01*
X305908Y30688D01*
X305993Y30616D01*
X306065Y30555D01*
X306113Y30507D01*
X306149Y30471D01*
X306161Y30459D01*
X306318Y30266D01*
X306462Y30062D01*
X306583Y29833D01*
X306691Y29616D01*
X306775Y29376D01*
X306847Y29147D01*
X306908Y28918D01*
X306956Y28701D01*
X307004Y28497D01*
X307028Y28304D01*
X307052Y28135D01*
X307064Y27979D01*
Y27859D01*
X307076Y27774D01*
Y27714D01*
Y27690D01*
X307064Y27377D01*
X307040Y27076D01*
X306992Y26799D01*
X306932Y26534D01*
X306871Y26305D01*
X306787Y26077D01*
X306703Y25884D01*
X306619Y25703D01*
X306534Y25535D01*
X306462Y25403D01*
X306378Y25282D01*
X306318Y25186D01*
X306257Y25101D01*
X306209Y25053D01*
X306185Y25017D01*
X306173Y25005D01*
X305993Y24837D01*
X305800Y24692D01*
X305607Y24560D01*
X305403Y24451D01*
X305198Y24367D01*
X304993Y24283D01*
X304789Y24223D01*
X304596Y24174D01*
X304415Y24138D01*
X304247Y24102D01*
X304090Y24078D01*
X303958Y24066D01*
X303850D01*
X303777Y24054D01*
X303705D01*
X303476Y24066D01*
X303260Y24078D01*
X303067Y24114D01*
X302874Y24150D01*
X302694Y24186D01*
X302525Y24247D01*
X302369Y24295D01*
X302236Y24355D01*
X302104Y24403D01*
X301996Y24463D01*
X301899Y24512D01*
X301827Y24548D01*
X301767Y24596D01*
X301719Y24620D01*
X301695Y24632D01*
X301682Y24644D01*
X301406Y24885D01*
X301177Y25162D01*
X300984Y25451D01*
X300840Y25715D01*
X300731Y25968D01*
X300695Y26065D01*
X300659Y26161D01*
X300635Y26233D01*
X300611Y26293D01*
X300599Y26330D01*
Y26342D01*
X301839Y26498D01*
X301947Y26233D01*
X302068Y26005D01*
X302188Y25800D01*
X302309Y25655D01*
X302405Y25535D01*
X302501Y25451D01*
X302549Y25390D01*
X302573Y25378D01*
X302754Y25270D01*
X302947Y25186D01*
X303139Y25126D01*
X303320Y25089D01*
X303476Y25065D01*
X303597Y25041D01*
X303705D01*
X303874Y25053D01*
X304030Y25065D01*
X304319Y25138D01*
X304572Y25234D01*
X304789Y25354D01*
X304957Y25463D01*
X305030Y25511D01*
X305090Y25559D01*
X305138Y25595D01*
X305174Y25631D01*
X305186Y25643D01*
X305198Y25655D01*
X305306Y25776D01*
X305391Y25908D01*
X305547Y26197D01*
X305668Y26498D01*
X305740Y26787D01*
X305776Y26920D01*
X305800Y27052D01*
X305812Y27160D01*
X305824Y27257D01*
X305836Y27341D01*
X305848Y27401D01*
Y27437D01*
Y27449D01*
X300563D01*
X300551Y27582D01*
Y27678D01*
Y27738D01*
Y27762D01*
X300563Y28075D01*
X300587Y28376D01*
X300635Y28665D01*
X300695Y28918D01*
X300755Y29159D01*
X300840Y29388D01*
X300912Y29592D01*
X300996Y29773D01*
X301080Y29929D01*
X301165Y30074D01*
X301249Y30194D01*
X301309Y30291D01*
X301369Y30375D01*
X301418Y30423D01*
X301442Y30459D01*
X301454Y30471D01*
X301622Y30640D01*
X301815Y30796D01*
X302008Y30929D01*
X302200Y31037D01*
X302393Y31133D01*
X302586Y31206D01*
X302778Y31278D01*
X302959Y31326D01*
X303127Y31362D01*
X303284Y31398D01*
X303416Y31422D01*
X303537Y31434D01*
X303645D01*
X303717Y31446D01*
X303777D01*
X304042Y31434D01*
D02*
G37*
G36*
X397000Y24211D02*
X395639D01*
X394580Y27160D01*
X390475D01*
X389355Y24211D01*
X387886D01*
X391871Y33975D01*
X393268D01*
X397000Y24211D01*
D02*
G37*
G36*
X384563Y31434D02*
X384708Y31410D01*
X384840Y31374D01*
X384948Y31326D01*
X385045Y31278D01*
X385117Y31242D01*
X385165Y31218D01*
X385177Y31206D01*
X385237Y31157D01*
X385309Y31097D01*
X385430Y30953D01*
X385562Y30784D01*
X385671Y30616D01*
X385779Y30459D01*
X385851Y30327D01*
X385887Y30278D01*
X385900Y30242D01*
X385924Y30218D01*
Y31290D01*
X387007D01*
Y24211D01*
X385803D01*
Y27907D01*
X385791Y28184D01*
X385767Y28449D01*
X385743Y28677D01*
X385707Y28894D01*
X385671Y29062D01*
X385635Y29195D01*
X385623Y29243D01*
Y29279D01*
X385611Y29291D01*
Y29303D01*
X385550Y29448D01*
X385490Y29580D01*
X385406Y29701D01*
X385334Y29797D01*
X385273Y29869D01*
X385213Y29917D01*
X385177Y29953D01*
X385165Y29966D01*
X385045Y30050D01*
X384924Y30110D01*
X384804Y30146D01*
X384696Y30182D01*
X384599Y30194D01*
X384527Y30206D01*
X384467D01*
X384310Y30194D01*
X384154Y30170D01*
X383997Y30122D01*
X383865Y30086D01*
X383756Y30038D01*
X383672Y29990D01*
X383624Y29966D01*
X383600Y29953D01*
X383178Y31061D01*
X383407Y31193D01*
X383636Y31290D01*
X383841Y31350D01*
X384021Y31398D01*
X384178Y31422D01*
X384298Y31446D01*
X384407D01*
X384563Y31434D01*
D02*
G37*
G36*
X360460D02*
X360713Y31398D01*
X360941Y31338D01*
X361158Y31266D01*
X361363Y31181D01*
X361543Y31073D01*
X361712Y30977D01*
X361868Y30868D01*
X362001Y30748D01*
X362109Y30652D01*
X362206Y30555D01*
X362290Y30459D01*
X362350Y30387D01*
X362398Y30327D01*
X362422Y30291D01*
X362434Y30278D01*
Y31290D01*
X363518D01*
Y24211D01*
X362314D01*
Y28075D01*
X362302Y28316D01*
X362290Y28545D01*
X362266Y28749D01*
X362230Y28942D01*
X362182Y29111D01*
X362133Y29255D01*
X362085Y29388D01*
X362037Y29508D01*
X361989Y29604D01*
X361941Y29689D01*
X361893Y29761D01*
X361844Y29821D01*
X361808Y29869D01*
X361784Y29893D01*
X361760Y29917D01*
X361543Y30086D01*
X361327Y30206D01*
X361098Y30291D01*
X360893Y30351D01*
X360713Y30387D01*
X360640Y30399D01*
X360580D01*
X360520Y30411D01*
X360448D01*
X360279Y30399D01*
X360111Y30375D01*
X359978Y30339D01*
X359846Y30303D01*
X359749Y30266D01*
X359677Y30230D01*
X359629Y30206D01*
X359617Y30194D01*
X359497Y30110D01*
X359388Y30014D01*
X359292Y29917D01*
X359232Y29821D01*
X359172Y29737D01*
X359136Y29664D01*
X359123Y29616D01*
X359111Y29604D01*
X359063Y29460D01*
X359027Y29279D01*
X359003Y29099D01*
X358979Y28918D01*
Y28761D01*
X358967Y28629D01*
Y28581D01*
Y28545D01*
Y28521D01*
Y28509D01*
Y24211D01*
X357775D01*
Y28557D01*
Y28846D01*
X357787Y29087D01*
X357799Y29291D01*
X357811Y29448D01*
X357823Y29580D01*
X357835Y29664D01*
X357847Y29713D01*
Y29725D01*
X357895Y29905D01*
X357956Y30074D01*
X358016Y30230D01*
X358076Y30351D01*
X358136Y30459D01*
X358172Y30543D01*
X358208Y30592D01*
X358220Y30604D01*
X358329Y30736D01*
X358461Y30856D01*
X358594Y30953D01*
X358726Y31049D01*
X358847Y31109D01*
X358943Y31170D01*
X359003Y31193D01*
X359015Y31206D01*
X359027D01*
X359232Y31290D01*
X359436Y31350D01*
X359629Y31386D01*
X359810Y31422D01*
X359966Y31434D01*
X360087Y31446D01*
X360195D01*
X360460Y31434D01*
D02*
G37*
G36*
X336826Y24211D02*
X335538D01*
Y28172D01*
X333034D01*
X332660Y28184D01*
X332311Y28208D01*
X331998Y28256D01*
X331709Y28304D01*
X331456Y28364D01*
X331216Y28437D01*
X331011Y28521D01*
X330818Y28605D01*
X330662Y28677D01*
X330529Y28761D01*
X330421Y28834D01*
X330325Y28894D01*
X330252Y28942D01*
X330204Y28990D01*
X330180Y29014D01*
X330168Y29026D01*
X330024Y29195D01*
X329903Y29364D01*
X329795Y29544D01*
X329711Y29725D01*
X329626Y29905D01*
X329566Y30074D01*
X329470Y30411D01*
X329434Y30568D01*
X329410Y30700D01*
X329398Y30832D01*
X329386Y30941D01*
X329374Y31025D01*
Y31085D01*
Y31133D01*
Y31145D01*
X329386Y31410D01*
X329422Y31663D01*
X329470Y31880D01*
X329518Y32085D01*
X329578Y32241D01*
X329626Y32361D01*
X329650Y32410D01*
X329663Y32446D01*
X329675Y32458D01*
Y32470D01*
X329795Y32686D01*
X329927Y32879D01*
X330060Y33036D01*
X330180Y33180D01*
X330289Y33276D01*
X330373Y33361D01*
X330433Y33409D01*
X330457Y33421D01*
X330650Y33541D01*
X330842Y33638D01*
X331047Y33710D01*
X331240Y33782D01*
X331408Y33818D01*
X331541Y33854D01*
X331589Y33866D01*
X331625Y33878D01*
X331661D01*
X331878Y33914D01*
X332107Y33939D01*
X332359Y33951D01*
X332600Y33963D01*
X332817Y33975D01*
X336826D01*
Y24211D01*
D02*
G37*
G36*
X327881D02*
X326677D01*
Y31290D01*
X327881D01*
Y24211D01*
D02*
G37*
G36*
X321801Y31434D02*
X322053Y31398D01*
X322282Y31338D01*
X322499Y31266D01*
X322704Y31181D01*
X322884Y31073D01*
X323053Y30977D01*
X323209Y30868D01*
X323342Y30748D01*
X323450Y30652D01*
X323546Y30555D01*
X323631Y30459D01*
X323691Y30387D01*
X323739Y30327D01*
X323763Y30291D01*
X323775Y30278D01*
Y31290D01*
X324859D01*
Y24211D01*
X323655D01*
Y28075D01*
X323643Y28316D01*
X323631Y28545D01*
X323607Y28749D01*
X323571Y28942D01*
X323522Y29111D01*
X323474Y29255D01*
X323426Y29388D01*
X323378Y29508D01*
X323330Y29604D01*
X323282Y29689D01*
X323233Y29761D01*
X323185Y29821D01*
X323149Y29869D01*
X323125Y29893D01*
X323101Y29917D01*
X322884Y30086D01*
X322668Y30206D01*
X322439Y30291D01*
X322234Y30351D01*
X322053Y30387D01*
X321981Y30399D01*
X321921D01*
X321861Y30411D01*
X321789D01*
X321620Y30399D01*
X321451Y30375D01*
X321319Y30339D01*
X321187Y30303D01*
X321090Y30266D01*
X321018Y30230D01*
X320970Y30206D01*
X320958Y30194D01*
X320838Y30110D01*
X320729Y30014D01*
X320633Y29917D01*
X320573Y29821D01*
X320512Y29737D01*
X320476Y29664D01*
X320464Y29616D01*
X320452Y29604D01*
X320404Y29460D01*
X320368Y29279D01*
X320344Y29099D01*
X320320Y28918D01*
Y28761D01*
X320308Y28629D01*
Y28581D01*
Y28545D01*
Y28521D01*
Y28509D01*
Y24211D01*
X319116D01*
Y28557D01*
Y28846D01*
X319128Y29087D01*
X319140Y29291D01*
X319152Y29448D01*
X319164Y29580D01*
X319176Y29664D01*
X319188Y29713D01*
Y29725D01*
X319236Y29905D01*
X319296Y30074D01*
X319357Y30230D01*
X319417Y30351D01*
X319477Y30459D01*
X319513Y30543D01*
X319549Y30592D01*
X319561Y30604D01*
X319670Y30736D01*
X319802Y30856D01*
X319935Y30953D01*
X320067Y31049D01*
X320187Y31109D01*
X320284Y31170D01*
X320344Y31193D01*
X320356Y31206D01*
X320368D01*
X320573Y31290D01*
X320777Y31350D01*
X320970Y31386D01*
X321151Y31422D01*
X321307Y31434D01*
X321427Y31446D01*
X321536D01*
X321801Y31434D01*
D02*
G37*
G36*
X309725Y24211D02*
X308521D01*
Y33975D01*
X309725D01*
Y24211D01*
D02*
G37*
G36*
X351454Y30471D02*
X351575Y30628D01*
X351719Y30760D01*
X351852Y30880D01*
X351984Y30989D01*
X352092Y31061D01*
X352189Y31121D01*
X352249Y31157D01*
X352273Y31170D01*
X352466Y31266D01*
X352658Y31326D01*
X352851Y31374D01*
X353019Y31410D01*
X353176Y31434D01*
X353296Y31446D01*
X353405D01*
X353718Y31422D01*
X354019Y31374D01*
X354283Y31302D01*
X354512Y31218D01*
X354717Y31121D01*
X354789Y31085D01*
X354861Y31049D01*
X354910Y31025D01*
X354946Y31001D01*
X354970Y30977D01*
X354982D01*
X355223Y30784D01*
X355439Y30580D01*
X355620Y30363D01*
X355764Y30146D01*
X355885Y29953D01*
X355921Y29869D01*
X355969Y29797D01*
X355993Y29737D01*
X356017Y29689D01*
X356029Y29664D01*
Y29653D01*
X356150Y29327D01*
X356234Y28990D01*
X356294Y28677D01*
X356330Y28376D01*
X356354Y28244D01*
Y28123D01*
X356366Y28015D01*
X356378Y27919D01*
Y27847D01*
Y27786D01*
Y27750D01*
Y27738D01*
X356366Y27341D01*
X356318Y26980D01*
X356258Y26655D01*
X356222Y26510D01*
X356186Y26366D01*
X356150Y26245D01*
X356114Y26137D01*
X356077Y26041D01*
X356053Y25956D01*
X356029Y25896D01*
X356005Y25848D01*
X355993Y25824D01*
Y25812D01*
X355837Y25523D01*
X355656Y25258D01*
X355475Y25041D01*
X355295Y24849D01*
X355138Y24704D01*
X355018Y24596D01*
X354970Y24560D01*
X354934Y24536D01*
X354910Y24512D01*
X354897D01*
X354621Y24355D01*
X354356Y24247D01*
X354091Y24162D01*
X353850Y24114D01*
X353645Y24078D01*
X353561Y24066D01*
X353489D01*
X353429Y24054D01*
X353344D01*
X353104Y24066D01*
X352887Y24102D01*
X352670Y24150D01*
X352478Y24223D01*
X352297Y24295D01*
X352140Y24391D01*
X351996Y24475D01*
X351864Y24584D01*
X351743Y24680D01*
X351635Y24776D01*
X351550Y24861D01*
X351478Y24933D01*
X351430Y25005D01*
X351394Y25053D01*
X351370Y25089D01*
X351358Y25101D01*
Y24211D01*
X350250D01*
Y33975D01*
X351454D01*
Y30471D01*
D02*
G37*
G36*
X345723Y31434D02*
X345952Y31410D01*
X346181Y31374D01*
X346385Y31326D01*
X346578Y31266D01*
X346759Y31193D01*
X346927Y31121D01*
X347084Y31049D01*
X347228Y30977D01*
X347349Y30905D01*
X347457Y30832D01*
X347541Y30772D01*
X347614Y30724D01*
X347662Y30688D01*
X347698Y30664D01*
X347710Y30652D01*
X347902Y30459D01*
X348071Y30254D01*
X348215Y30038D01*
X348336Y29797D01*
X348444Y29568D01*
X348529Y29327D01*
X348601Y29087D01*
X348661Y28846D01*
X348697Y28629D01*
X348733Y28424D01*
X348757Y28232D01*
X348781Y28075D01*
Y27943D01*
X348793Y27834D01*
Y27774D01*
Y27750D01*
X348781Y27425D01*
X348757Y27112D01*
X348709Y26835D01*
X348649Y26570D01*
X348577Y26318D01*
X348504Y26089D01*
X348420Y25884D01*
X348336Y25703D01*
X348252Y25547D01*
X348167Y25403D01*
X348095Y25282D01*
X348023Y25186D01*
X347963Y25101D01*
X347915Y25053D01*
X347891Y25017D01*
X347878Y25005D01*
X347698Y24837D01*
X347517Y24692D01*
X347313Y24560D01*
X347120Y24451D01*
X346915Y24367D01*
X346723Y24283D01*
X346518Y24223D01*
X346337Y24174D01*
X346157Y24138D01*
X346000Y24102D01*
X345856Y24078D01*
X345723Y24066D01*
X345627D01*
X345543Y24054D01*
X345482D01*
X345145Y24078D01*
X344820Y24126D01*
X344531Y24186D01*
X344279Y24271D01*
X344170Y24307D01*
X344074Y24343D01*
X343978Y24379D01*
X343905Y24415D01*
X343845Y24439D01*
X343809Y24463D01*
X343785Y24475D01*
X343773D01*
X343496Y24656D01*
X343255Y24849D01*
X343050Y25053D01*
X342882Y25246D01*
X342750Y25427D01*
X342653Y25559D01*
X342629Y25619D01*
X342605Y25655D01*
X342581Y25679D01*
Y25691D01*
X342509Y25848D01*
X342449Y26005D01*
X342340Y26354D01*
X342268Y26715D01*
X342220Y27064D01*
X342208Y27220D01*
X342196Y27377D01*
X342184Y27509D01*
X342172Y27618D01*
Y27714D01*
Y27786D01*
Y27834D01*
Y27847D01*
X342184Y28160D01*
X342208Y28449D01*
X342256Y28713D01*
X342316Y28966D01*
X342388Y29207D01*
X342461Y29424D01*
X342545Y29616D01*
X342629Y29797D01*
X342725Y29953D01*
X342810Y30098D01*
X342882Y30206D01*
X342954Y30315D01*
X343014Y30387D01*
X343063Y30435D01*
X343087Y30471D01*
X343099Y30483D01*
X343279Y30652D01*
X343472Y30796D01*
X343665Y30929D01*
X343857Y31037D01*
X344062Y31133D01*
X344254Y31218D01*
X344447Y31278D01*
X344640Y31326D01*
X344808Y31362D01*
X344977Y31398D01*
X345121Y31422D01*
X345242Y31434D01*
X345338Y31446D01*
X345482D01*
X345723Y31434D01*
D02*
G37*
G36*
X297156Y31422D02*
X297324Y31398D01*
X297481Y31374D01*
X297613Y31350D01*
X297709Y31326D01*
X297770Y31314D01*
X297794Y31302D01*
X297962Y31242D01*
X298119Y31181D01*
X298251Y31133D01*
X298360Y31073D01*
X298444Y31025D01*
X298516Y30989D01*
X298552Y30965D01*
X298564Y30953D01*
X298697Y30844D01*
X298817Y30724D01*
X298913Y30616D01*
X298998Y30507D01*
X299070Y30411D01*
X299118Y30339D01*
X299142Y30291D01*
X299154Y30266D01*
X299226Y30110D01*
X299275Y29966D01*
X299311Y29821D01*
X299335Y29689D01*
X299347Y29568D01*
X299359Y29484D01*
Y29424D01*
Y29400D01*
X299347Y29207D01*
X299323Y29038D01*
X299275Y28870D01*
X299226Y28725D01*
X299190Y28617D01*
X299142Y28521D01*
X299118Y28473D01*
X299106Y28449D01*
X298998Y28304D01*
X298877Y28172D01*
X298745Y28051D01*
X298624Y27955D01*
X298504Y27883D01*
X298420Y27822D01*
X298360Y27786D01*
X298335Y27774D01*
X298227Y27726D01*
X298107Y27678D01*
X297974Y27630D01*
X297830Y27582D01*
X297529Y27485D01*
X297228Y27401D01*
X297083Y27365D01*
X296951Y27329D01*
X296831Y27293D01*
X296722Y27269D01*
X296626Y27245D01*
X296566Y27220D01*
X296518Y27208D01*
X296506D01*
X296325Y27160D01*
X296168Y27124D01*
X296024Y27076D01*
X295891Y27040D01*
X295783Y27004D01*
X295687Y26968D01*
X295590Y26932D01*
X295518Y26907D01*
X295410Y26859D01*
X295326Y26823D01*
X295289Y26811D01*
X295277Y26799D01*
X295157Y26703D01*
X295073Y26606D01*
X295000Y26498D01*
X294964Y26390D01*
X294940Y26305D01*
X294916Y26233D01*
Y26185D01*
Y26161D01*
X294928Y25992D01*
X294976Y25848D01*
X295049Y25703D01*
X295121Y25595D01*
X295193Y25499D01*
X295265Y25427D01*
X295313Y25378D01*
X295326Y25366D01*
X295494Y25258D01*
X295687Y25174D01*
X295891Y25126D01*
X296084Y25077D01*
X296265Y25053D01*
X296349D01*
X296421Y25041D01*
X296554D01*
X296843Y25053D01*
X297095Y25101D01*
X297312Y25162D01*
X297493Y25234D01*
X297637Y25294D01*
X297745Y25354D01*
X297806Y25403D01*
X297830Y25415D01*
X297986Y25571D01*
X298107Y25740D01*
X298203Y25920D01*
X298275Y26101D01*
X298323Y26257D01*
X298360Y26390D01*
X298372Y26438D01*
X298384Y26474D01*
Y26498D01*
Y26510D01*
X299564Y26330D01*
X299515Y26125D01*
X299467Y25932D01*
X299407Y25752D01*
X299335Y25583D01*
X299263Y25427D01*
X299190Y25294D01*
X299106Y25162D01*
X299034Y25053D01*
X298962Y24945D01*
X298889Y24861D01*
X298817Y24788D01*
X298769Y24728D01*
X298721Y24680D01*
X298685Y24644D01*
X298661Y24632D01*
X298648Y24620D01*
X298504Y24524D01*
X298347Y24439D01*
X298010Y24295D01*
X297661Y24199D01*
X297324Y24126D01*
X297168Y24102D01*
X297023Y24090D01*
X296879Y24066D01*
X296770D01*
X296674Y24054D01*
X296542D01*
X296241Y24066D01*
X295964Y24102D01*
X295711Y24150D01*
X295494Y24199D01*
X295313Y24247D01*
X295241Y24271D01*
X295169Y24295D01*
X295121Y24319D01*
X295085Y24331D01*
X295073Y24343D01*
X295061D01*
X294832Y24463D01*
X294627Y24596D01*
X294447Y24728D01*
X294302Y24861D01*
X294194Y24981D01*
X294110Y25077D01*
X294061Y25138D01*
X294049Y25162D01*
X293929Y25366D01*
X293845Y25559D01*
X293773Y25752D01*
X293736Y25920D01*
X293712Y26065D01*
X293688Y26185D01*
Y26257D01*
Y26269D01*
Y26281D01*
X293700Y26498D01*
X293736Y26703D01*
X293785Y26871D01*
X293833Y27028D01*
X293881Y27148D01*
X293929Y27232D01*
X293965Y27281D01*
X293977Y27305D01*
X294097Y27449D01*
X294218Y27582D01*
X294350Y27690D01*
X294483Y27786D01*
X294591Y27847D01*
X294688Y27907D01*
X294748Y27931D01*
X294772Y27943D01*
X294868Y27991D01*
X294988Y28027D01*
X295121Y28075D01*
X295253Y28123D01*
X295542Y28208D01*
X295843Y28304D01*
X296108Y28376D01*
X296229Y28412D01*
X296337Y28437D01*
X296421Y28461D01*
X296481Y28485D01*
X296530Y28497D01*
X296542D01*
X296698Y28545D01*
X296843Y28581D01*
X296963Y28617D01*
X297083Y28641D01*
X297180Y28677D01*
X297264Y28701D01*
X297396Y28737D01*
X297493Y28761D01*
X297553Y28786D01*
X297589Y28798D01*
X297601D01*
X297709Y28846D01*
X297806Y28906D01*
X297878Y28954D01*
X297950Y29014D01*
X297998Y29051D01*
X298034Y29087D01*
X298046Y29111D01*
X298059Y29123D01*
X298107Y29195D01*
X298143Y29267D01*
X298179Y29400D01*
X298191Y29460D01*
X298203Y29508D01*
Y29532D01*
Y29544D01*
X298191Y29676D01*
X298143Y29797D01*
X298095Y29905D01*
X298022Y30002D01*
X297962Y30074D01*
X297902Y30134D01*
X297866Y30170D01*
X297854Y30182D01*
X297697Y30278D01*
X297517Y30339D01*
X297324Y30387D01*
X297132Y30423D01*
X296951Y30447D01*
X296806Y30459D01*
X296674D01*
X296421Y30447D01*
X296204Y30411D01*
X296024Y30363D01*
X295867Y30303D01*
X295747Y30242D01*
X295663Y30194D01*
X295602Y30158D01*
X295590Y30146D01*
X295458Y30026D01*
X295350Y29893D01*
X295277Y29749D01*
X295205Y29616D01*
X295169Y29496D01*
X295145Y29388D01*
X295121Y29327D01*
Y29315D01*
Y29303D01*
X293953Y29460D01*
X294001Y29701D01*
X294074Y29917D01*
X294134Y30110D01*
X294206Y30266D01*
X294278Y30387D01*
X294326Y30483D01*
X294362Y30531D01*
X294374Y30555D01*
X294495Y30700D01*
X294651Y30832D01*
X294796Y30941D01*
X294952Y31037D01*
X295085Y31109D01*
X295193Y31157D01*
X295277Y31193D01*
X295289Y31206D01*
X295301D01*
X295542Y31290D01*
X295795Y31350D01*
X296036Y31386D01*
X296265Y31422D01*
X296457Y31434D01*
X296542D01*
X296614Y31446D01*
X296963D01*
X297156Y31422D01*
D02*
G37*
G36*
X379049Y20572D02*
X377845D01*
Y21933D01*
X379049D01*
Y20572D01*
D02*
G37*
G36*
X323041Y19392D02*
X323282Y19356D01*
X323486Y19296D01*
X323679Y19248D01*
X323823Y19188D01*
X323944Y19127D01*
X324016Y19091D01*
X324028Y19079D01*
X324040D01*
X324233Y18959D01*
X324413Y18814D01*
X324570Y18682D01*
X324690Y18549D01*
X324799Y18429D01*
X324871Y18333D01*
X324919Y18273D01*
X324931Y18261D01*
Y19248D01*
X326003D01*
Y12169D01*
X324799D01*
Y15841D01*
X324786Y16178D01*
X324762Y16479D01*
X324738Y16732D01*
X324702Y16936D01*
X324666Y17105D01*
X324630Y17213D01*
X324618Y17285D01*
X324606Y17309D01*
X324522Y17490D01*
X324425Y17647D01*
X324329Y17779D01*
X324221Y17899D01*
X324136Y17984D01*
X324064Y18044D01*
X324016Y18080D01*
X323992Y18092D01*
X323823Y18188D01*
X323667Y18249D01*
X323498Y18297D01*
X323354Y18333D01*
X323233Y18357D01*
X323137Y18369D01*
X323053D01*
X322812Y18357D01*
X322619Y18309D01*
X322451Y18237D01*
X322318Y18164D01*
X322222Y18092D01*
X322150Y18020D01*
X322102Y17972D01*
X322090Y17960D01*
X321993Y17791D01*
X321921Y17610D01*
X321873Y17406D01*
X321837Y17213D01*
X321813Y17045D01*
X321801Y16900D01*
Y16840D01*
Y16804D01*
Y16780D01*
Y16768D01*
Y12169D01*
X320597D01*
Y16274D01*
Y16479D01*
X320573Y16659D01*
X320549Y16828D01*
X320524Y16984D01*
X320476Y17129D01*
X320440Y17261D01*
X320392Y17382D01*
X320344Y17478D01*
X320308Y17574D01*
X320260Y17647D01*
X320211Y17719D01*
X320175Y17767D01*
X320151Y17815D01*
X320127Y17839D01*
X320103Y17863D01*
X319910Y18032D01*
X319706Y18152D01*
X319489Y18249D01*
X319296Y18309D01*
X319128Y18345D01*
X318983Y18357D01*
X318935Y18369D01*
X318863D01*
X318706Y18357D01*
X318574Y18333D01*
X318454Y18309D01*
X318345Y18273D01*
X318261Y18225D01*
X318189Y18200D01*
X318153Y18176D01*
X318141Y18164D01*
X318032Y18092D01*
X317948Y18008D01*
X317864Y17924D01*
X317815Y17839D01*
X317767Y17767D01*
X317743Y17707D01*
X317719Y17671D01*
Y17659D01*
X317683Y17526D01*
X317647Y17370D01*
X317623Y17189D01*
X317611Y17020D01*
X317599Y16864D01*
Y16744D01*
Y16695D01*
Y16659D01*
Y16635D01*
Y16623D01*
Y12169D01*
X316395D01*
Y17020D01*
Y17237D01*
X316419Y17442D01*
X316443Y17635D01*
X316479Y17815D01*
X316527Y17972D01*
X316576Y18128D01*
X316624Y18261D01*
X316672Y18369D01*
X316732Y18477D01*
X316780Y18574D01*
X316828Y18646D01*
X316877Y18706D01*
X316913Y18754D01*
X316937Y18790D01*
X316949Y18802D01*
X316961Y18814D01*
X317069Y18923D01*
X317190Y19007D01*
X317322Y19091D01*
X317454Y19152D01*
X317719Y19260D01*
X317984Y19332D01*
X318225Y19368D01*
X318321Y19392D01*
X318405D01*
X318490Y19404D01*
X318586D01*
X318827Y19392D01*
X319068Y19356D01*
X319284Y19296D01*
X319501Y19212D01*
X319694Y19115D01*
X319874Y19007D01*
X320043Y18899D01*
X320187Y18790D01*
X320320Y18670D01*
X320440Y18562D01*
X320536Y18453D01*
X320621Y18357D01*
X320693Y18285D01*
X320741Y18212D01*
X320765Y18176D01*
X320777Y18164D01*
X320874Y18369D01*
X320982Y18549D01*
X321102Y18706D01*
X321223Y18838D01*
X321331Y18935D01*
X321415Y19007D01*
X321476Y19055D01*
X321500Y19067D01*
X321692Y19176D01*
X321909Y19260D01*
X322126Y19320D01*
X322330Y19368D01*
X322511Y19392D01*
X322583D01*
X322655Y19404D01*
X322788D01*
X323041Y19392D01*
D02*
G37*
G36*
X373378D02*
X373679Y19368D01*
X373956Y19320D01*
X374185Y19284D01*
X374293Y19260D01*
X374390Y19236D01*
X374462Y19212D01*
X374534Y19188D01*
X374582Y19176D01*
X374618Y19164D01*
X374642Y19152D01*
X374655D01*
X374895Y19043D01*
X375112Y18935D01*
X375293Y18814D01*
X375437Y18694D01*
X375558Y18586D01*
X375642Y18501D01*
X375702Y18453D01*
X375714Y18429D01*
X375834Y18249D01*
X375943Y18044D01*
X376039Y17851D01*
X376111Y17659D01*
X376159Y17490D01*
X376196Y17346D01*
X376220Y17297D01*
Y17261D01*
X376232Y17237D01*
Y17225D01*
X375064Y17069D01*
X374980Y17334D01*
X374895Y17550D01*
X374787Y17731D01*
X374691Y17875D01*
X374606Y17984D01*
X374534Y18056D01*
X374486Y18104D01*
X374474Y18116D01*
X374305Y18212D01*
X374101Y18285D01*
X373896Y18345D01*
X373691Y18381D01*
X373499Y18405D01*
X373414D01*
X373354Y18417D01*
X373210D01*
X372885Y18405D01*
X372608Y18357D01*
X372367Y18285D01*
X372174Y18212D01*
X372030Y18140D01*
X371922Y18068D01*
X371861Y18020D01*
X371837Y18008D01*
X371717Y17875D01*
X371633Y17719D01*
X371572Y17550D01*
X371536Y17382D01*
X371500Y17225D01*
X371488Y17093D01*
Y17045D01*
Y17009D01*
Y16984D01*
Y16972D01*
Y16936D01*
Y16888D01*
Y16792D01*
X371500Y16744D01*
Y16695D01*
Y16671D01*
Y16659D01*
X371633Y16611D01*
X371789Y16575D01*
X372126Y16491D01*
X372475Y16418D01*
X372825Y16358D01*
X372993Y16334D01*
X373149Y16310D01*
X373282Y16286D01*
X373402Y16274D01*
X373499Y16262D01*
X373583Y16250D01*
X373631Y16238D01*
X373643D01*
X373896Y16202D01*
X374113Y16178D01*
X374293Y16142D01*
X374450Y16118D01*
X374570Y16093D01*
X374642Y16069D01*
X374703Y16057D01*
X374715D01*
X374895Y15997D01*
X375052Y15937D01*
X375196Y15877D01*
X375329Y15805D01*
X375437Y15756D01*
X375509Y15708D01*
X375569Y15672D01*
X375582Y15660D01*
X375714Y15564D01*
X375846Y15443D01*
X375943Y15335D01*
X376039Y15227D01*
X376111Y15130D01*
X376159Y15046D01*
X376196Y14998D01*
X376208Y14974D01*
X376280Y14817D01*
X376340Y14649D01*
X376376Y14492D01*
X376412Y14348D01*
X376424Y14215D01*
X376436Y14119D01*
Y14059D01*
Y14047D01*
Y14035D01*
X376424Y13866D01*
X376412Y13722D01*
X376340Y13433D01*
X376244Y13180D01*
X376123Y12975D01*
X376003Y12807D01*
X375907Y12686D01*
X375871Y12638D01*
X375834Y12602D01*
X375822Y12590D01*
X375810Y12578D01*
X375690Y12482D01*
X375558Y12397D01*
X375269Y12253D01*
X374967Y12156D01*
X374679Y12084D01*
X374546Y12060D01*
X374414Y12048D01*
X374305Y12024D01*
X374209D01*
X374125Y12012D01*
X374016D01*
X373751Y12024D01*
X373511Y12048D01*
X373282Y12084D01*
X373089Y12132D01*
X372921Y12169D01*
X372800Y12205D01*
X372752Y12217D01*
X372716Y12229D01*
X372704Y12241D01*
X372692D01*
X372451Y12349D01*
X372223Y12470D01*
X372006Y12602D01*
X371801Y12746D01*
X371633Y12867D01*
X371512Y12963D01*
X371452Y12999D01*
X371416Y13035D01*
X371404Y13047D01*
X371392Y13060D01*
X371368Y12879D01*
X371332Y12698D01*
X371307Y12554D01*
X371259Y12421D01*
X371235Y12313D01*
X371199Y12241D01*
X371187Y12181D01*
X371175Y12169D01*
X369923D01*
X369995Y12325D01*
X370055Y12470D01*
X370103Y12614D01*
X370152Y12734D01*
X370176Y12855D01*
X370200Y12939D01*
X370212Y12987D01*
Y13011D01*
X370224Y13108D01*
X370236Y13228D01*
X370248Y13372D01*
Y13529D01*
X370272Y13878D01*
Y14239D01*
Y14408D01*
X370284Y14576D01*
Y14733D01*
Y14865D01*
Y14974D01*
Y15058D01*
Y15106D01*
Y15130D01*
Y16732D01*
Y17009D01*
X370296Y17237D01*
X370308Y17430D01*
Y17586D01*
X370320Y17695D01*
X370332Y17779D01*
X370344Y17827D01*
Y17839D01*
X370392Y18008D01*
X370453Y18164D01*
X370513Y18309D01*
X370573Y18429D01*
X370633Y18513D01*
X370681Y18586D01*
X370718Y18634D01*
X370730Y18646D01*
X370838Y18766D01*
X370970Y18863D01*
X371103Y18959D01*
X371247Y19043D01*
X371368Y19103D01*
X371464Y19152D01*
X371536Y19176D01*
X371548Y19188D01*
X371560D01*
X371789Y19260D01*
X372030Y19308D01*
X372283Y19356D01*
X372511Y19380D01*
X372716Y19392D01*
X372812D01*
X372885Y19404D01*
X373041D01*
X373378Y19392D01*
D02*
G37*
G36*
X330927D02*
X331228Y19368D01*
X331505Y19320D01*
X331733Y19284D01*
X331842Y19260D01*
X331938Y19236D01*
X332010Y19212D01*
X332082Y19188D01*
X332131Y19176D01*
X332167Y19164D01*
X332191Y19152D01*
X332203D01*
X332444Y19043D01*
X332660Y18935D01*
X332841Y18814D01*
X332985Y18694D01*
X333106Y18586D01*
X333190Y18501D01*
X333250Y18453D01*
X333262Y18429D01*
X333383Y18249D01*
X333491Y18044D01*
X333587Y17851D01*
X333660Y17659D01*
X333708Y17490D01*
X333744Y17346D01*
X333768Y17297D01*
Y17261D01*
X333780Y17237D01*
Y17225D01*
X332612Y17069D01*
X332528Y17334D01*
X332444Y17550D01*
X332335Y17731D01*
X332239Y17875D01*
X332155Y17984D01*
X332082Y18056D01*
X332034Y18104D01*
X332022Y18116D01*
X331854Y18212D01*
X331649Y18285D01*
X331444Y18345D01*
X331240Y18381D01*
X331047Y18405D01*
X330963D01*
X330903Y18417D01*
X330758D01*
X330433Y18405D01*
X330156Y18357D01*
X329915Y18285D01*
X329723Y18212D01*
X329578Y18140D01*
X329470Y18068D01*
X329410Y18020D01*
X329386Y18008D01*
X329265Y17875D01*
X329181Y17719D01*
X329121Y17550D01*
X329085Y17382D01*
X329049Y17225D01*
X329036Y17093D01*
Y17045D01*
Y17009D01*
Y16984D01*
Y16972D01*
Y16936D01*
Y16888D01*
Y16792D01*
X329049Y16744D01*
Y16695D01*
Y16671D01*
Y16659D01*
X329181Y16611D01*
X329337Y16575D01*
X329675Y16491D01*
X330024Y16418D01*
X330373Y16358D01*
X330541Y16334D01*
X330698Y16310D01*
X330830Y16286D01*
X330951Y16274D01*
X331047Y16262D01*
X331131Y16250D01*
X331180Y16238D01*
X331191D01*
X331444Y16202D01*
X331661Y16178D01*
X331842Y16142D01*
X331998Y16118D01*
X332119Y16093D01*
X332191Y16069D01*
X332251Y16057D01*
X332263D01*
X332444Y15997D01*
X332600Y15937D01*
X332745Y15877D01*
X332877Y15805D01*
X332985Y15756D01*
X333058Y15708D01*
X333118Y15672D01*
X333130Y15660D01*
X333262Y15564D01*
X333395Y15443D01*
X333491Y15335D01*
X333587Y15227D01*
X333660Y15130D01*
X333708Y15046D01*
X333744Y14998D01*
X333756Y14974D01*
X333828Y14817D01*
X333888Y14649D01*
X333924Y14492D01*
X333961Y14348D01*
X333973Y14215D01*
X333985Y14119D01*
Y14059D01*
Y14047D01*
Y14035D01*
X333973Y13866D01*
X333961Y13722D01*
X333888Y13433D01*
X333792Y13180D01*
X333672Y12975D01*
X333551Y12807D01*
X333455Y12686D01*
X333419Y12638D01*
X333383Y12602D01*
X333371Y12590D01*
X333359Y12578D01*
X333238Y12482D01*
X333106Y12397D01*
X332817Y12253D01*
X332516Y12156D01*
X332227Y12084D01*
X332094Y12060D01*
X331962Y12048D01*
X331854Y12024D01*
X331757D01*
X331673Y12012D01*
X331565D01*
X331300Y12024D01*
X331059Y12048D01*
X330830Y12084D01*
X330638Y12132D01*
X330469Y12169D01*
X330349Y12205D01*
X330301Y12217D01*
X330265Y12229D01*
X330252Y12241D01*
X330240D01*
X330000Y12349D01*
X329771Y12470D01*
X329554Y12602D01*
X329350Y12746D01*
X329181Y12867D01*
X329061Y12963D01*
X329000Y12999D01*
X328964Y13035D01*
X328952Y13047D01*
X328940Y13060D01*
X328916Y12879D01*
X328880Y12698D01*
X328856Y12554D01*
X328808Y12421D01*
X328784Y12313D01*
X328747Y12241D01*
X328736Y12181D01*
X328723Y12169D01*
X327471D01*
X327543Y12325D01*
X327604Y12470D01*
X327652Y12614D01*
X327700Y12734D01*
X327724Y12855D01*
X327748Y12939D01*
X327760Y12987D01*
Y13011D01*
X327772Y13108D01*
X327784Y13228D01*
X327796Y13372D01*
Y13529D01*
X327821Y13878D01*
Y14239D01*
Y14408D01*
X327832Y14576D01*
Y14733D01*
Y14865D01*
Y14974D01*
Y15058D01*
Y15106D01*
Y15130D01*
Y16732D01*
Y17009D01*
X327845Y17237D01*
X327857Y17430D01*
Y17586D01*
X327869Y17695D01*
X327881Y17779D01*
X327893Y17827D01*
Y17839D01*
X327941Y18008D01*
X328001Y18164D01*
X328061Y18309D01*
X328121Y18429D01*
X328182Y18513D01*
X328230Y18586D01*
X328266Y18634D01*
X328278Y18646D01*
X328386Y18766D01*
X328519Y18863D01*
X328651Y18959D01*
X328796Y19043D01*
X328916Y19103D01*
X329012Y19152D01*
X329085Y19176D01*
X329097Y19188D01*
X329109D01*
X329337Y19260D01*
X329578Y19308D01*
X329831Y19356D01*
X330060Y19380D01*
X330265Y19392D01*
X330361D01*
X330433Y19404D01*
X330590D01*
X330927Y19392D01*
D02*
G37*
G36*
X347770Y20994D02*
Y19248D01*
X348661D01*
Y18321D01*
X347770D01*
Y14239D01*
Y14047D01*
X347758Y13866D01*
Y13710D01*
X347746Y13565D01*
X347734Y13433D01*
X347722Y13312D01*
X347710Y13216D01*
X347698Y13120D01*
X347686Y13047D01*
X347674Y12987D01*
X347650Y12891D01*
X347626Y12831D01*
Y12819D01*
X347565Y12698D01*
X347481Y12590D01*
X347409Y12494D01*
X347325Y12421D01*
X347252Y12361D01*
X347192Y12313D01*
X347144Y12289D01*
X347132Y12277D01*
X346987Y12205D01*
X346819Y12156D01*
X346650Y12120D01*
X346494Y12096D01*
X346349Y12084D01*
X346229Y12072D01*
X346121D01*
X345808Y12084D01*
X345651Y12108D01*
X345507Y12120D01*
X345386Y12145D01*
X345290Y12156D01*
X345230Y12169D01*
X345206D01*
X345362Y13228D01*
X345482Y13216D01*
X345591Y13204D01*
X345675D01*
X345747Y13192D01*
X345892D01*
X346073Y13204D01*
X346133Y13216D01*
X346193Y13240D01*
X346241Y13252D01*
X346277Y13264D01*
X346289Y13276D01*
X346301D01*
X346398Y13348D01*
X346458Y13421D01*
X346494Y13481D01*
X346506Y13505D01*
X346530Y13577D01*
X346542Y13673D01*
X346554Y13782D01*
Y13890D01*
X346566Y13999D01*
Y14083D01*
Y14143D01*
Y14167D01*
Y18321D01*
X345362D01*
Y19248D01*
X346566D01*
Y21716D01*
X347770Y20994D01*
D02*
G37*
G36*
X389692Y14853D02*
Y14589D01*
X389680Y14360D01*
X389668Y14167D01*
X389656Y14011D01*
X389644Y13890D01*
X389632Y13806D01*
X389620Y13746D01*
Y13734D01*
X389572Y13553D01*
X389523Y13372D01*
X389463Y13228D01*
X389403Y13096D01*
X389343Y12987D01*
X389307Y12915D01*
X389271Y12855D01*
X389258Y12843D01*
X389150Y12710D01*
X389018Y12602D01*
X388885Y12494D01*
X388753Y12409D01*
X388633Y12337D01*
X388536Y12289D01*
X388476Y12253D01*
X388452Y12241D01*
X388247Y12169D01*
X388031Y12108D01*
X387838Y12072D01*
X387657Y12036D01*
X387501Y12024D01*
X387380Y12012D01*
X387272D01*
X387007Y12024D01*
X386766Y12060D01*
X386538Y12120D01*
X386321Y12205D01*
X386116Y12289D01*
X385936Y12385D01*
X385767Y12494D01*
X385611Y12614D01*
X385478Y12722D01*
X385358Y12831D01*
X385261Y12927D01*
X385177Y13023D01*
X385105Y13096D01*
X385057Y13156D01*
X385033Y13192D01*
X385021Y13204D01*
Y12169D01*
X383949D01*
Y19248D01*
X385153D01*
Y15455D01*
X385165Y15142D01*
X385189Y14853D01*
X385213Y14625D01*
X385249Y14420D01*
X385298Y14275D01*
X385322Y14155D01*
X385346Y14095D01*
X385358Y14071D01*
X385442Y13902D01*
X385538Y13746D01*
X385659Y13625D01*
X385767Y13517D01*
X385863Y13421D01*
X385948Y13361D01*
X386008Y13324D01*
X386032Y13312D01*
X386213Y13228D01*
X386381Y13156D01*
X386550Y13108D01*
X386706Y13084D01*
X386839Y13060D01*
X386935Y13047D01*
X387031D01*
X387224Y13060D01*
X387404Y13084D01*
X387561Y13132D01*
X387693Y13180D01*
X387802Y13228D01*
X387874Y13276D01*
X387934Y13300D01*
X387946Y13312D01*
X388067Y13421D01*
X388175Y13541D01*
X388247Y13662D01*
X388319Y13782D01*
X388368Y13890D01*
X388392Y13974D01*
X388416Y14035D01*
Y14059D01*
X388428Y14131D01*
X388440Y14203D01*
X388452Y14396D01*
X388476Y14601D01*
Y14817D01*
X388488Y15010D01*
Y15094D01*
Y15166D01*
Y15239D01*
Y15287D01*
Y15311D01*
Y15323D01*
Y19248D01*
X389692D01*
Y14853D01*
D02*
G37*
G36*
X312013Y19392D02*
X312277Y19368D01*
X312518Y19308D01*
X312735Y19248D01*
X312952Y19176D01*
X313144Y19091D01*
X313325Y19007D01*
X313493Y18911D01*
X313638Y18814D01*
X313758Y18730D01*
X313879Y18646D01*
X313963Y18574D01*
X314035Y18513D01*
X314083Y18465D01*
X314119Y18429D01*
X314131Y18417D01*
X314288Y18225D01*
X314432Y18020D01*
X314553Y17791D01*
X314661Y17574D01*
X314745Y17334D01*
X314818Y17105D01*
X314878Y16876D01*
X314926Y16659D01*
X314974Y16455D01*
X314998Y16262D01*
X315022Y16093D01*
X315034Y15937D01*
Y15817D01*
X315046Y15732D01*
Y15672D01*
Y15648D01*
X315034Y15335D01*
X315010Y15034D01*
X314962Y14757D01*
X314902Y14492D01*
X314842Y14263D01*
X314757Y14035D01*
X314673Y13842D01*
X314589Y13662D01*
X314505Y13493D01*
X314432Y13361D01*
X314348Y13240D01*
X314288Y13144D01*
X314228Y13060D01*
X314180Y13011D01*
X314156Y12975D01*
X314144Y12963D01*
X313963Y12795D01*
X313770Y12650D01*
X313578Y12518D01*
X313373Y12409D01*
X313168Y12325D01*
X312964Y12241D01*
X312759Y12181D01*
X312566Y12132D01*
X312386Y12096D01*
X312217Y12060D01*
X312061Y12036D01*
X311928Y12024D01*
X311820D01*
X311748Y12012D01*
X311675D01*
X311447Y12024D01*
X311230Y12036D01*
X311037Y12072D01*
X310845Y12108D01*
X310664Y12145D01*
X310495Y12205D01*
X310339Y12253D01*
X310207Y12313D01*
X310074Y12361D01*
X309966Y12421D01*
X309869Y12470D01*
X309797Y12506D01*
X309737Y12554D01*
X309689Y12578D01*
X309665Y12590D01*
X309653Y12602D01*
X309376Y12843D01*
X309147Y13120D01*
X308954Y13409D01*
X308810Y13673D01*
X308702Y13926D01*
X308665Y14023D01*
X308629Y14119D01*
X308605Y14191D01*
X308581Y14251D01*
X308569Y14288D01*
Y14300D01*
X309809Y14456D01*
X309918Y14191D01*
X310038Y13963D01*
X310158Y13758D01*
X310279Y13613D01*
X310375Y13493D01*
X310471Y13409D01*
X310520Y13348D01*
X310544Y13336D01*
X310724Y13228D01*
X310917Y13144D01*
X311110Y13084D01*
X311290Y13047D01*
X311447Y13023D01*
X311567Y12999D01*
X311675D01*
X311844Y13011D01*
X312000Y13023D01*
X312289Y13096D01*
X312542Y13192D01*
X312759Y13312D01*
X312927Y13421D01*
X313000Y13469D01*
X313060Y13517D01*
X313108Y13553D01*
X313144Y13589D01*
X313156Y13601D01*
X313168Y13613D01*
X313277Y13734D01*
X313361Y13866D01*
X313517Y14155D01*
X313638Y14456D01*
X313710Y14745D01*
X313746Y14878D01*
X313770Y15010D01*
X313782Y15118D01*
X313794Y15215D01*
X313806Y15299D01*
X313818Y15359D01*
Y15395D01*
Y15407D01*
X308533D01*
X308521Y15540D01*
Y15636D01*
Y15696D01*
Y15720D01*
X308533Y16033D01*
X308557Y16334D01*
X308605Y16623D01*
X308665Y16876D01*
X308726Y17117D01*
X308810Y17346D01*
X308882Y17550D01*
X308966Y17731D01*
X309051Y17887D01*
X309135Y18032D01*
X309219Y18152D01*
X309279Y18249D01*
X309340Y18333D01*
X309388Y18381D01*
X309412Y18417D01*
X309424Y18429D01*
X309592Y18598D01*
X309785Y18754D01*
X309978Y18887D01*
X310170Y18995D01*
X310363Y19091D01*
X310556Y19164D01*
X310748Y19236D01*
X310929Y19284D01*
X311097Y19320D01*
X311254Y19356D01*
X311386Y19380D01*
X311507Y19392D01*
X311615D01*
X311687Y19404D01*
X311748D01*
X312013Y19392D01*
D02*
G37*
G36*
X382107Y12169D02*
X380903D01*
Y21933D01*
X382107D01*
Y12169D01*
D02*
G37*
G36*
X379049D02*
X377845D01*
Y19248D01*
X379049D01*
Y12169D01*
D02*
G37*
G36*
X365384Y19392D02*
X365637Y19356D01*
X365866Y19296D01*
X366082Y19224D01*
X366287Y19139D01*
X366468Y19031D01*
X366636Y18935D01*
X366793Y18827D01*
X366925Y18706D01*
X367033Y18610D01*
X367130Y18513D01*
X367214Y18417D01*
X367274Y18345D01*
X367322Y18285D01*
X367346Y18249D01*
X367359Y18237D01*
Y19248D01*
X368442D01*
Y12169D01*
X367238D01*
Y16033D01*
X367226Y16274D01*
X367214Y16503D01*
X367190Y16708D01*
X367154Y16900D01*
X367106Y17069D01*
X367057Y17213D01*
X367009Y17346D01*
X366961Y17466D01*
X366913Y17562D01*
X366865Y17647D01*
X366817Y17719D01*
X366769Y17779D01*
X366732Y17827D01*
X366708Y17851D01*
X366684Y17875D01*
X366468Y18044D01*
X366251Y18164D01*
X366022Y18249D01*
X365817Y18309D01*
X365637Y18345D01*
X365565Y18357D01*
X365504D01*
X365444Y18369D01*
X365372D01*
X365203Y18357D01*
X365035Y18333D01*
X364902Y18297D01*
X364770Y18261D01*
X364674Y18225D01*
X364601Y18188D01*
X364553Y18164D01*
X364541Y18152D01*
X364421Y18068D01*
X364313Y17972D01*
X364216Y17875D01*
X364156Y17779D01*
X364096Y17695D01*
X364060Y17622D01*
X364048Y17574D01*
X364036Y17562D01*
X363987Y17418D01*
X363951Y17237D01*
X363927Y17057D01*
X363903Y16876D01*
Y16719D01*
X363891Y16587D01*
Y16539D01*
Y16503D01*
Y16479D01*
Y16467D01*
Y12169D01*
X362699D01*
Y16515D01*
Y16804D01*
X362711Y17045D01*
X362723Y17249D01*
X362735Y17406D01*
X362747Y17538D01*
X362759Y17622D01*
X362771Y17671D01*
Y17683D01*
X362820Y17863D01*
X362880Y18032D01*
X362940Y18188D01*
X363000Y18309D01*
X363060Y18417D01*
X363097Y18501D01*
X363133Y18549D01*
X363145Y18562D01*
X363253Y18694D01*
X363385Y18814D01*
X363518Y18911D01*
X363650Y19007D01*
X363771Y19067D01*
X363867Y19127D01*
X363927Y19152D01*
X363939Y19164D01*
X363951D01*
X364156Y19248D01*
X364361Y19308D01*
X364553Y19344D01*
X364734Y19380D01*
X364890Y19392D01*
X365011Y19404D01*
X365119D01*
X365384Y19392D01*
D02*
G37*
G36*
X305126Y19380D02*
X305294Y19356D01*
X305451Y19332D01*
X305583Y19308D01*
X305680Y19284D01*
X305740Y19272D01*
X305764Y19260D01*
X305933Y19200D01*
X306089Y19139D01*
X306221Y19091D01*
X306330Y19031D01*
X306414Y18983D01*
X306486Y18947D01*
X306522Y18923D01*
X306534Y18911D01*
X306667Y18802D01*
X306787Y18682D01*
X306884Y18574D01*
X306968Y18465D01*
X307040Y18369D01*
X307088Y18297D01*
X307112Y18249D01*
X307124Y18225D01*
X307197Y18068D01*
X307245Y17924D01*
X307281Y17779D01*
X307305Y17647D01*
X307317Y17526D01*
X307329Y17442D01*
Y17382D01*
Y17358D01*
X307317Y17165D01*
X307293Y16996D01*
X307245Y16828D01*
X307197Y16683D01*
X307160Y16575D01*
X307112Y16479D01*
X307088Y16431D01*
X307076Y16407D01*
X306968Y16262D01*
X306847Y16130D01*
X306715Y16009D01*
X306595Y15913D01*
X306474Y15841D01*
X306390Y15780D01*
X306330Y15744D01*
X306306Y15732D01*
X306197Y15684D01*
X306077Y15636D01*
X305944Y15588D01*
X305800Y15540D01*
X305499Y15443D01*
X305198Y15359D01*
X305054Y15323D01*
X304921Y15287D01*
X304801Y15251D01*
X304692Y15227D01*
X304596Y15202D01*
X304536Y15179D01*
X304488Y15166D01*
X304476D01*
X304295Y15118D01*
X304139Y15082D01*
X303994Y15034D01*
X303862Y14998D01*
X303753Y14962D01*
X303657Y14926D01*
X303561Y14890D01*
X303488Y14865D01*
X303380Y14817D01*
X303296Y14781D01*
X303260Y14769D01*
X303248Y14757D01*
X303127Y14661D01*
X303043Y14564D01*
X302971Y14456D01*
X302935Y14348D01*
X302910Y14263D01*
X302886Y14191D01*
Y14143D01*
Y14119D01*
X302899Y13950D01*
X302947Y13806D01*
X303019Y13662D01*
X303091Y13553D01*
X303163Y13457D01*
X303236Y13385D01*
X303284Y13336D01*
X303296Y13324D01*
X303464Y13216D01*
X303657Y13132D01*
X303862Y13084D01*
X304054Y13035D01*
X304235Y13011D01*
X304319D01*
X304391Y12999D01*
X304524D01*
X304813Y13011D01*
X305066Y13060D01*
X305282Y13120D01*
X305463Y13192D01*
X305607Y13252D01*
X305716Y13312D01*
X305776Y13361D01*
X305800Y13372D01*
X305956Y13529D01*
X306077Y13698D01*
X306173Y13878D01*
X306245Y14059D01*
X306294Y14215D01*
X306330Y14348D01*
X306342Y14396D01*
X306354Y14432D01*
Y14456D01*
Y14468D01*
X307534Y14288D01*
X307486Y14083D01*
X307437Y13890D01*
X307377Y13710D01*
X307305Y13541D01*
X307233Y13385D01*
X307160Y13252D01*
X307076Y13120D01*
X307004Y13011D01*
X306932Y12903D01*
X306859Y12819D01*
X306787Y12746D01*
X306739Y12686D01*
X306691Y12638D01*
X306655Y12602D01*
X306631Y12590D01*
X306619Y12578D01*
X306474Y12482D01*
X306318Y12397D01*
X305981Y12253D01*
X305632Y12156D01*
X305294Y12084D01*
X305138Y12060D01*
X304993Y12048D01*
X304849Y12024D01*
X304741D01*
X304644Y12012D01*
X304512D01*
X304211Y12024D01*
X303934Y12060D01*
X303681Y12108D01*
X303464Y12156D01*
X303284Y12205D01*
X303211Y12229D01*
X303139Y12253D01*
X303091Y12277D01*
X303055Y12289D01*
X303043Y12301D01*
X303031D01*
X302802Y12421D01*
X302598Y12554D01*
X302417Y12686D01*
X302272Y12819D01*
X302164Y12939D01*
X302080Y13035D01*
X302032Y13096D01*
X302020Y13120D01*
X301899Y13324D01*
X301815Y13517D01*
X301743Y13710D01*
X301707Y13878D01*
X301682Y14023D01*
X301658Y14143D01*
Y14215D01*
Y14227D01*
Y14239D01*
X301670Y14456D01*
X301707Y14661D01*
X301755Y14829D01*
X301803Y14986D01*
X301851Y15106D01*
X301899Y15191D01*
X301935Y15239D01*
X301947Y15263D01*
X302068Y15407D01*
X302188Y15540D01*
X302321Y15648D01*
X302453Y15744D01*
X302561Y15805D01*
X302658Y15865D01*
X302718Y15889D01*
X302742Y15901D01*
X302838Y15949D01*
X302959Y15985D01*
X303091Y16033D01*
X303223Y16081D01*
X303512Y16166D01*
X303813Y16262D01*
X304078Y16334D01*
X304199Y16370D01*
X304307Y16394D01*
X304391Y16418D01*
X304452Y16443D01*
X304500Y16455D01*
X304512D01*
X304668Y16503D01*
X304813Y16539D01*
X304933Y16575D01*
X305054Y16599D01*
X305150Y16635D01*
X305234Y16659D01*
X305367Y16695D01*
X305463Y16719D01*
X305523Y16744D01*
X305559Y16756D01*
X305571D01*
X305680Y16804D01*
X305776Y16864D01*
X305848Y16912D01*
X305920Y16972D01*
X305969Y17009D01*
X306005Y17045D01*
X306017Y17069D01*
X306029Y17081D01*
X306077Y17153D01*
X306113Y17225D01*
X306149Y17358D01*
X306161Y17418D01*
X306173Y17466D01*
Y17490D01*
Y17502D01*
X306161Y17635D01*
X306113Y17755D01*
X306065Y17863D01*
X305993Y17960D01*
X305933Y18032D01*
X305872Y18092D01*
X305836Y18128D01*
X305824Y18140D01*
X305668Y18237D01*
X305487Y18297D01*
X305294Y18345D01*
X305102Y18381D01*
X304921Y18405D01*
X304777Y18417D01*
X304644D01*
X304391Y18405D01*
X304175Y18369D01*
X303994Y18321D01*
X303838Y18261D01*
X303717Y18200D01*
X303633Y18152D01*
X303573Y18116D01*
X303561Y18104D01*
X303428Y17984D01*
X303320Y17851D01*
X303248Y17707D01*
X303175Y17574D01*
X303139Y17454D01*
X303115Y17346D01*
X303091Y17285D01*
Y17273D01*
Y17261D01*
X301923Y17418D01*
X301971Y17659D01*
X302044Y17875D01*
X302104Y18068D01*
X302176Y18225D01*
X302248Y18345D01*
X302297Y18441D01*
X302333Y18489D01*
X302345Y18513D01*
X302465Y18658D01*
X302622Y18790D01*
X302766Y18899D01*
X302923Y18995D01*
X303055Y19067D01*
X303163Y19115D01*
X303248Y19152D01*
X303260Y19164D01*
X303272D01*
X303512Y19248D01*
X303765Y19308D01*
X304006Y19344D01*
X304235Y19380D01*
X304428Y19392D01*
X304512D01*
X304584Y19404D01*
X304933D01*
X305126Y19380D01*
D02*
G37*
G36*
X392906Y15202D02*
Y14914D01*
X392931Y14661D01*
X392955Y14444D01*
X392979Y14275D01*
X393003Y14143D01*
X393027Y14047D01*
X393039Y13999D01*
X393051Y13974D01*
X393111Y13842D01*
X393183Y13722D01*
X393256Y13625D01*
X393340Y13529D01*
X393412Y13469D01*
X393472Y13409D01*
X393521Y13385D01*
X393533Y13372D01*
X393665Y13300D01*
X393810Y13252D01*
X393954Y13204D01*
X394074Y13180D01*
X394195Y13168D01*
X394279Y13156D01*
X394363D01*
X394592Y13168D01*
X394809Y13216D01*
X394977Y13276D01*
X395134Y13361D01*
X395242Y13433D01*
X395326Y13493D01*
X395387Y13541D01*
X395399Y13553D01*
X395459Y13637D01*
X395519Y13734D01*
X395615Y13963D01*
X395688Y14215D01*
X395748Y14468D01*
X395772Y14709D01*
X395784Y14805D01*
X395796Y14901D01*
Y14974D01*
X395808Y15034D01*
Y15070D01*
Y15082D01*
X396976Y14914D01*
Y14649D01*
X396964Y14408D01*
X396928Y14179D01*
X396892Y13963D01*
X396843Y13770D01*
X396795Y13589D01*
X396735Y13433D01*
X396675Y13288D01*
X396603Y13156D01*
X396554Y13047D01*
X396494Y12951D01*
X396446Y12867D01*
X396398Y12807D01*
X396362Y12771D01*
X396350Y12746D01*
X396338Y12734D01*
X396205Y12602D01*
X396061Y12494D01*
X395904Y12397D01*
X395736Y12313D01*
X395579Y12241D01*
X395411Y12181D01*
X395098Y12096D01*
X394941Y12060D01*
X394809Y12036D01*
X394688Y12024D01*
X394580Y12012D01*
X394484Y12000D01*
X394363D01*
X394050Y12012D01*
X393761Y12060D01*
X393508Y12108D01*
X393280Y12181D01*
X393111Y12241D01*
X393027Y12265D01*
X392967Y12301D01*
X392919Y12313D01*
X392882Y12337D01*
X392870Y12349D01*
X392858D01*
X392630Y12494D01*
X392437Y12662D01*
X392281Y12831D01*
X392148Y12987D01*
X392052Y13144D01*
X391979Y13264D01*
X391955Y13312D01*
X391931Y13348D01*
X391919Y13361D01*
Y13372D01*
X391871Y13505D01*
X391823Y13649D01*
X391751Y13950D01*
X391690Y14275D01*
X391654Y14576D01*
X391642Y14721D01*
X391630Y14853D01*
Y14974D01*
X391618Y15070D01*
Y15154D01*
Y15227D01*
Y15263D01*
Y15275D01*
Y21933D01*
X392906D01*
Y15202D01*
D02*
G37*
G36*
X353910Y22089D02*
X354247Y22053D01*
X354548Y21993D01*
X354813Y21933D01*
X354934Y21897D01*
X355030Y21872D01*
X355126Y21848D01*
X355199Y21812D01*
X355259Y21800D01*
X355307Y21776D01*
X355331Y21764D01*
X355343D01*
X355632Y21620D01*
X355873Y21463D01*
X356089Y21307D01*
X356258Y21150D01*
X356390Y21006D01*
X356487Y20885D01*
X356523Y20837D01*
X356547Y20801D01*
X356571Y20789D01*
Y20777D01*
X356703Y20536D01*
X356812Y20295D01*
X356884Y20055D01*
X356932Y19850D01*
X356956Y19657D01*
X356968Y19585D01*
Y19525D01*
X356980Y19465D01*
Y19428D01*
Y19404D01*
Y19392D01*
X356968Y19152D01*
X356932Y18923D01*
X356872Y18706D01*
X356812Y18537D01*
X356752Y18381D01*
X356691Y18273D01*
X356655Y18200D01*
X356643Y18188D01*
Y18176D01*
X356499Y17984D01*
X356342Y17803D01*
X356162Y17659D01*
X355993Y17526D01*
X355849Y17418D01*
X355716Y17334D01*
X355680Y17309D01*
X355644Y17285D01*
X355620Y17273D01*
X355608D01*
X355499Y17225D01*
X355367Y17165D01*
X355235Y17105D01*
X355090Y17057D01*
X354777Y16948D01*
X354464Y16864D01*
X354320Y16816D01*
X354175Y16780D01*
X354055Y16744D01*
X353946Y16719D01*
X353862Y16695D01*
X353790Y16671D01*
X353742Y16659D01*
X353730D01*
X353489Y16599D01*
X353272Y16551D01*
X353068Y16491D01*
X352887Y16443D01*
X352730Y16407D01*
X352586Y16370D01*
X352453Y16334D01*
X352345Y16298D01*
X352261Y16274D01*
X352177Y16250D01*
X352116Y16226D01*
X352068Y16202D01*
X352032Y16190D01*
X352008D01*
X351984Y16178D01*
X351767Y16093D01*
X351587Y15997D01*
X351430Y15889D01*
X351310Y15805D01*
X351225Y15720D01*
X351153Y15660D01*
X351117Y15612D01*
X351105Y15600D01*
X351009Y15467D01*
X350948Y15335D01*
X350900Y15202D01*
X350864Y15082D01*
X350840Y14974D01*
X350828Y14878D01*
Y14829D01*
Y14805D01*
X350840Y14637D01*
X350876Y14492D01*
X350912Y14348D01*
X350961Y14227D01*
X351021Y14119D01*
X351057Y14047D01*
X351093Y13987D01*
X351105Y13974D01*
X351225Y13842D01*
X351358Y13722D01*
X351490Y13613D01*
X351635Y13529D01*
X351755Y13457D01*
X351852Y13409D01*
X351924Y13385D01*
X351936Y13372D01*
X351948D01*
X352164Y13300D01*
X352393Y13252D01*
X352610Y13204D01*
X352815Y13180D01*
X352983Y13168D01*
X353128Y13156D01*
X353248D01*
X353549Y13168D01*
X353838Y13204D01*
X354091Y13252D01*
X354308Y13300D01*
X354500Y13348D01*
X354572Y13372D01*
X354633Y13397D01*
X354681Y13421D01*
X354717Y13433D01*
X354741Y13445D01*
X354753D01*
X354982Y13565D01*
X355187Y13685D01*
X355355Y13818D01*
X355488Y13938D01*
X355596Y14035D01*
X355668Y14131D01*
X355716Y14179D01*
X355728Y14203D01*
X355837Y14396D01*
X355921Y14589D01*
X355993Y14793D01*
X356041Y14986D01*
X356077Y15154D01*
X356101Y15287D01*
X356114Y15335D01*
X356126Y15371D01*
Y15395D01*
Y15407D01*
X357342Y15299D01*
X357318Y14938D01*
X357245Y14613D01*
X357161Y14312D01*
X357065Y14047D01*
X357016Y13938D01*
X356968Y13842D01*
X356932Y13746D01*
X356896Y13673D01*
X356860Y13613D01*
X356836Y13577D01*
X356812Y13553D01*
Y13541D01*
X356607Y13276D01*
X356378Y13035D01*
X356150Y12843D01*
X355921Y12674D01*
X355728Y12554D01*
X355632Y12494D01*
X355560Y12457D01*
X355499Y12421D01*
X355451Y12409D01*
X355427Y12385D01*
X355415D01*
X355066Y12253D01*
X354693Y12169D01*
X354320Y12096D01*
X353970Y12048D01*
X353814Y12036D01*
X353657Y12024D01*
X353537Y12012D01*
X353417D01*
X353332Y12000D01*
X353200D01*
X352815Y12012D01*
X352466Y12060D01*
X352140Y12120D01*
X351996Y12156D01*
X351864Y12193D01*
X351743Y12217D01*
X351635Y12253D01*
X351550Y12289D01*
X351466Y12313D01*
X351406Y12337D01*
X351358Y12361D01*
X351334Y12373D01*
X351322D01*
X351021Y12530D01*
X350768Y12698D01*
X350539Y12879D01*
X350359Y13060D01*
X350214Y13204D01*
X350118Y13336D01*
X350082Y13385D01*
X350058Y13421D01*
X350033Y13433D01*
Y13445D01*
X349889Y13710D01*
X349781Y13963D01*
X349696Y14215D01*
X349648Y14432D01*
X349612Y14625D01*
X349600Y14709D01*
Y14781D01*
X349588Y14841D01*
Y14878D01*
Y14901D01*
Y14914D01*
X349600Y15202D01*
X349648Y15455D01*
X349720Y15696D01*
X349793Y15901D01*
X349865Y16069D01*
X349937Y16190D01*
X349961Y16238D01*
X349985Y16274D01*
X349997Y16286D01*
Y16298D01*
X350166Y16515D01*
X350371Y16708D01*
X350575Y16876D01*
X350780Y17020D01*
X350973Y17141D01*
X351045Y17189D01*
X351117Y17225D01*
X351177Y17261D01*
X351225Y17285D01*
X351250Y17297D01*
X351262D01*
X351382Y17346D01*
X351514Y17406D01*
X351671Y17454D01*
X351839Y17502D01*
X352201Y17610D01*
X352550Y17707D01*
X352730Y17743D01*
X352887Y17791D01*
X353031Y17827D01*
X353164Y17851D01*
X353272Y17875D01*
X353344Y17899D01*
X353393Y17911D01*
X353417D01*
X353694Y17984D01*
X353958Y18044D01*
X354187Y18116D01*
X354392Y18176D01*
X354572Y18237D01*
X354729Y18297D01*
X354861Y18345D01*
X354982Y18393D01*
X355078Y18441D01*
X355162Y18489D01*
X355235Y18526D01*
X355283Y18549D01*
X355319Y18574D01*
X355343Y18598D01*
X355367Y18610D01*
X355488Y18742D01*
X355584Y18887D01*
X355644Y19031D01*
X355692Y19176D01*
X355716Y19296D01*
X355728Y19392D01*
X355740Y19453D01*
Y19477D01*
X355728Y19585D01*
X355716Y19693D01*
X355656Y19898D01*
X355572Y20066D01*
X355475Y20223D01*
X355379Y20343D01*
X355295Y20440D01*
X355235Y20488D01*
X355210Y20512D01*
X355102Y20584D01*
X354982Y20656D01*
X354717Y20765D01*
X354428Y20837D01*
X354151Y20897D01*
X353898Y20921D01*
X353790Y20933D01*
X353694D01*
X353609Y20945D01*
X353296D01*
X353104Y20921D01*
X352923Y20897D01*
X352766Y20873D01*
X352610Y20837D01*
X352466Y20801D01*
X352345Y20753D01*
X352237Y20717D01*
X352128Y20668D01*
X352044Y20620D01*
X351972Y20584D01*
X351912Y20548D01*
X351864Y20524D01*
X351827Y20500D01*
X351815Y20476D01*
X351803D01*
X351611Y20283D01*
X351454Y20066D01*
X351334Y19838D01*
X351237Y19609D01*
X351177Y19404D01*
X351165Y19320D01*
X351141Y19248D01*
X351129Y19176D01*
X351117Y19127D01*
Y19103D01*
Y19091D01*
X349877Y19188D01*
X349913Y19501D01*
X349961Y19790D01*
X350046Y20043D01*
X350130Y20271D01*
X350214Y20464D01*
X350250Y20536D01*
X350286Y20596D01*
X350322Y20644D01*
X350335Y20681D01*
X350359Y20705D01*
Y20717D01*
X350539Y20958D01*
X350744Y21162D01*
X350961Y21343D01*
X351165Y21487D01*
X351346Y21596D01*
X351430Y21644D01*
X351502Y21680D01*
X351550Y21704D01*
X351599Y21728D01*
X351623Y21740D01*
X351635D01*
X351960Y21860D01*
X352285Y21945D01*
X352610Y22017D01*
X352899Y22053D01*
X353043Y22077D01*
X353164D01*
X353272Y22089D01*
X353368Y22101D01*
X353549D01*
X353910Y22089D01*
D02*
G37*
G36*
X336826Y15202D02*
Y14914D01*
X336850Y14661D01*
X336874Y14444D01*
X336898Y14275D01*
X336922Y14143D01*
X336946Y14047D01*
X336959Y13999D01*
X336970Y13974D01*
X337031Y13842D01*
X337103Y13722D01*
X337175Y13625D01*
X337259Y13529D01*
X337332Y13469D01*
X337392Y13409D01*
X337440Y13385D01*
X337452Y13372D01*
X337585Y13300D01*
X337729Y13252D01*
X337873Y13204D01*
X337994Y13180D01*
X338114Y13168D01*
X338199Y13156D01*
X338283D01*
X338512Y13168D01*
X338728Y13216D01*
X338897Y13276D01*
X339053Y13361D01*
X339162Y13433D01*
X339246Y13493D01*
X339306Y13541D01*
X339318Y13553D01*
X339379Y13637D01*
X339439Y13734D01*
X339535Y13963D01*
X339607Y14215D01*
X339667Y14468D01*
X339692Y14709D01*
X339703Y14805D01*
X339716Y14901D01*
Y14974D01*
X339728Y15034D01*
Y15070D01*
Y15082D01*
X340896Y14914D01*
Y14649D01*
X340883Y14408D01*
X340847Y14179D01*
X340811Y13963D01*
X340763Y13770D01*
X340715Y13589D01*
X340655Y13433D01*
X340594Y13288D01*
X340522Y13156D01*
X340474Y13047D01*
X340414Y12951D01*
X340366Y12867D01*
X340318Y12807D01*
X340281Y12771D01*
X340269Y12746D01*
X340257Y12734D01*
X340125Y12602D01*
X339980Y12494D01*
X339824Y12397D01*
X339655Y12313D01*
X339499Y12241D01*
X339330Y12181D01*
X339017Y12096D01*
X338861Y12060D01*
X338728Y12036D01*
X338608Y12024D01*
X338500Y12012D01*
X338403Y12000D01*
X338283D01*
X337970Y12012D01*
X337681Y12060D01*
X337428Y12108D01*
X337199Y12181D01*
X337031Y12241D01*
X336946Y12265D01*
X336886Y12301D01*
X336838Y12313D01*
X336802Y12337D01*
X336790Y12349D01*
X336778D01*
X336549Y12494D01*
X336357Y12662D01*
X336200Y12831D01*
X336068Y12987D01*
X335971Y13144D01*
X335899Y13264D01*
X335875Y13312D01*
X335851Y13348D01*
X335839Y13361D01*
Y13372D01*
X335791Y13505D01*
X335742Y13649D01*
X335670Y13950D01*
X335610Y14275D01*
X335574Y14576D01*
X335562Y14721D01*
X335550Y14853D01*
Y14974D01*
X335538Y15070D01*
Y15154D01*
Y15227D01*
Y15263D01*
Y15275D01*
Y21933D01*
X336826D01*
Y15202D01*
D02*
G37*
%LPC*%
G36*
X349082Y207376D02*
X344001D01*
Y207239D01*
X341941D01*
Y207102D01*
X340705D01*
Y206964D01*
X339607D01*
Y206827D01*
X338508D01*
Y206690D01*
X337685D01*
Y206552D01*
X336861D01*
Y206415D01*
X336174D01*
Y206278D01*
X335487D01*
Y206140D01*
X334801D01*
Y206003D01*
X334252D01*
Y205866D01*
X333702D01*
Y205728D01*
X333153D01*
Y205591D01*
X332604D01*
Y205454D01*
X332192D01*
Y205317D01*
X331642D01*
Y205179D01*
X331231D01*
Y205042D01*
X330819D01*
Y204905D01*
X330269D01*
Y204767D01*
X329857D01*
Y204630D01*
X329445D01*
Y204493D01*
X329171D01*
Y204355D01*
X328759D01*
Y204218D01*
X328347D01*
Y204081D01*
X327935D01*
Y203943D01*
X327660D01*
Y203806D01*
X327248D01*
Y203669D01*
X326836D01*
Y203531D01*
X326562D01*
Y203394D01*
X326150D01*
Y203257D01*
X325875D01*
Y203119D01*
X325601D01*
Y202982D01*
X325189D01*
Y202845D01*
X324914D01*
Y202708D01*
X324639D01*
Y202570D01*
X324365D01*
Y202433D01*
X324090D01*
Y202295D01*
X323678D01*
Y202158D01*
X323404D01*
Y202021D01*
X323266D01*
Y201884D01*
X322991D01*
Y201746D01*
X322580D01*
Y201609D01*
X322305D01*
Y201472D01*
X322168D01*
Y201334D01*
X321756D01*
Y201197D01*
X321618D01*
Y201060D01*
X321344D01*
Y200922D01*
X321069D01*
Y200785D01*
X320794D01*
Y200648D01*
X320520D01*
Y200510D01*
X320382D01*
Y200373D01*
X320108D01*
Y200236D01*
X319833D01*
Y200098D01*
X319559D01*
Y199961D01*
X319421D01*
Y199824D01*
X319147D01*
Y199687D01*
X318872D01*
Y199549D01*
X318735D01*
Y199412D01*
X318460D01*
Y199275D01*
X318323D01*
Y199137D01*
X318048D01*
Y199000D01*
X317773D01*
Y198863D01*
X317636D01*
Y198725D01*
X317362D01*
Y198588D01*
X317224D01*
Y198451D01*
X316950D01*
Y198313D01*
X316812D01*
Y198176D01*
X316538D01*
Y198039D01*
X316400D01*
Y197901D01*
X316126D01*
Y197764D01*
X315988D01*
Y197627D01*
X315851D01*
Y197489D01*
X315576D01*
Y197352D01*
X315439D01*
Y197215D01*
X315302D01*
Y197078D01*
X315027D01*
Y196940D01*
X314890D01*
Y196803D01*
X314615D01*
Y196665D01*
X314478D01*
Y196528D01*
X314340D01*
Y196391D01*
X314203D01*
Y196254D01*
X313929D01*
Y196116D01*
X313791D01*
Y195979D01*
X313654D01*
Y195842D01*
X313379D01*
Y195704D01*
X313242D01*
Y195567D01*
X313105D01*
Y195430D01*
X312967D01*
Y195292D01*
X312830D01*
Y195155D01*
X312555D01*
Y195018D01*
X312418D01*
Y194880D01*
X312281D01*
Y194743D01*
X312143D01*
Y194606D01*
X312006D01*
Y194468D01*
X311731D01*
Y194331D01*
X311594D01*
Y194194D01*
X311457D01*
Y194056D01*
X311320D01*
Y193919D01*
X311182D01*
Y193782D01*
X311045D01*
Y193645D01*
X310908D01*
Y193507D01*
X310770D01*
Y193370D01*
X310633D01*
Y193233D01*
X310358D01*
Y193095D01*
X310221D01*
Y192958D01*
X310084D01*
Y192821D01*
X309946D01*
Y192683D01*
X309809D01*
Y192546D01*
X309672D01*
Y192409D01*
X309534D01*
Y192271D01*
X309397D01*
Y192134D01*
X309260D01*
Y191997D01*
X309122D01*
Y191859D01*
X308985D01*
Y191722D01*
X308848D01*
Y191585D01*
X308710D01*
Y191447D01*
X308573D01*
Y191310D01*
X308436D01*
Y191173D01*
X308298D01*
Y191035D01*
X308161D01*
Y190898D01*
X308024D01*
Y190761D01*
X307887D01*
Y190623D01*
X307749D01*
Y190486D01*
X307612D01*
Y190349D01*
X307475D01*
Y190212D01*
Y190074D01*
X307337D01*
Y189937D01*
X307200D01*
Y189800D01*
X307063D01*
Y189662D01*
X306925D01*
Y189525D01*
X306788D01*
Y189388D01*
X306651D01*
Y189250D01*
X306513D01*
Y189113D01*
X306376D01*
Y188976D01*
Y188838D01*
X306239D01*
Y188701D01*
X306101D01*
Y188564D01*
X305964D01*
Y188426D01*
X305827D01*
Y188289D01*
X305690D01*
Y188152D01*
Y188015D01*
X305552D01*
Y187877D01*
X305415D01*
Y187740D01*
X305278D01*
Y187603D01*
X305140D01*
Y187465D01*
X305003D01*
Y187328D01*
Y187191D01*
X304866D01*
Y187053D01*
X304728D01*
Y186916D01*
X304591D01*
Y186779D01*
Y186641D01*
X304454D01*
Y186504D01*
X304316D01*
Y186367D01*
X304179D01*
Y186229D01*
X304042D01*
Y186092D01*
Y185955D01*
X303904D01*
Y185817D01*
X303767D01*
Y185680D01*
X303630D01*
Y185543D01*
Y185406D01*
X303492D01*
Y185268D01*
X303355D01*
Y185131D01*
Y184993D01*
X303218D01*
Y184856D01*
X303081D01*
Y184719D01*
X302943D01*
Y184582D01*
Y184444D01*
X302806D01*
Y184307D01*
X302668D01*
Y184170D01*
Y184032D01*
X302531D01*
Y183895D01*
X302394D01*
Y183758D01*
Y183620D01*
X302257D01*
Y183483D01*
X302119D01*
Y183346D01*
Y183208D01*
X301982D01*
Y183071D01*
X301845D01*
Y182934D01*
Y182796D01*
X301707D01*
Y182659D01*
X301570D01*
Y182522D01*
Y182384D01*
X301433D01*
Y182247D01*
Y182110D01*
X301295D01*
Y181973D01*
X301158D01*
Y181835D01*
Y181698D01*
X301021D01*
Y181561D01*
Y181423D01*
X300883D01*
Y181286D01*
X300746D01*
Y181149D01*
Y181011D01*
X300609D01*
Y180874D01*
Y180737D01*
X300471D01*
Y180599D01*
X300334D01*
Y180462D01*
Y180325D01*
X300197D01*
Y180187D01*
Y180050D01*
X300060D01*
Y179913D01*
Y179776D01*
X299922D01*
Y179638D01*
Y179501D01*
X299785D01*
Y179363D01*
X299648D01*
Y179226D01*
Y179089D01*
X299510D01*
Y178952D01*
Y178814D01*
X299373D01*
Y178677D01*
Y178540D01*
X299236D01*
Y178402D01*
Y178265D01*
X299098D01*
Y178128D01*
Y177990D01*
X298961D01*
Y177853D01*
Y177716D01*
X298824D01*
Y177578D01*
Y177441D01*
X298686D01*
Y177304D01*
Y177166D01*
X298549D01*
Y177029D01*
Y176892D01*
X298412D01*
Y176754D01*
Y176617D01*
Y176480D01*
X298274D01*
Y176343D01*
Y176205D01*
X298137D01*
Y176068D01*
Y175931D01*
X298000D01*
Y175793D01*
Y175656D01*
X297862D01*
Y175519D01*
Y175381D01*
Y175244D01*
X297725D01*
Y175107D01*
Y174969D01*
X297588D01*
Y174832D01*
Y174695D01*
X297451D01*
Y174557D01*
Y174420D01*
Y174283D01*
X297313D01*
Y174145D01*
Y174008D01*
X297176D01*
Y173871D01*
Y173734D01*
Y173596D01*
X297038D01*
Y173459D01*
Y173321D01*
X296901D01*
Y173184D01*
Y173047D01*
Y172910D01*
X296764D01*
Y172772D01*
Y172635D01*
Y172498D01*
X296627D01*
Y172360D01*
Y172223D01*
X296489D01*
Y172086D01*
Y171948D01*
Y171811D01*
X296352D01*
Y171674D01*
Y171536D01*
Y171399D01*
X296215D01*
Y171262D01*
Y171124D01*
Y170987D01*
X296077D01*
Y170850D01*
Y170713D01*
Y170575D01*
X295940D01*
Y170438D01*
Y170301D01*
Y170163D01*
X295803D01*
Y170026D01*
Y169889D01*
Y169751D01*
Y169614D01*
X295665D01*
Y169477D01*
Y169339D01*
Y169202D01*
X295528D01*
Y169065D01*
Y168927D01*
Y168790D01*
Y168653D01*
X295391D01*
Y168515D01*
Y168378D01*
Y168241D01*
X295253D01*
Y168104D01*
Y167966D01*
Y167829D01*
Y167691D01*
X295116D01*
Y167554D01*
Y167417D01*
Y167280D01*
Y167142D01*
X294979D01*
Y167005D01*
Y166868D01*
Y166730D01*
Y166593D01*
X294841D01*
Y166456D01*
Y166318D01*
Y166181D01*
Y166044D01*
X294704D01*
Y165906D01*
Y165769D01*
Y165632D01*
Y165494D01*
Y165357D01*
X294567D01*
Y165220D01*
Y165082D01*
Y164945D01*
Y164808D01*
Y164671D01*
X294429D01*
Y164533D01*
Y164396D01*
Y164259D01*
Y164121D01*
Y163984D01*
X294292D01*
Y163847D01*
Y163709D01*
Y163572D01*
Y163435D01*
Y163297D01*
X294155D01*
Y163160D01*
Y163023D01*
Y162885D01*
Y162748D01*
Y162611D01*
Y162473D01*
X294018D01*
Y162336D01*
Y162199D01*
Y162062D01*
Y161924D01*
Y161787D01*
Y161649D01*
Y161512D01*
X293880D01*
Y161375D01*
Y161238D01*
Y161100D01*
Y160963D01*
Y160826D01*
Y160688D01*
Y160551D01*
Y160414D01*
X293743D01*
Y160276D01*
Y160139D01*
Y160002D01*
Y159864D01*
Y159727D01*
Y159590D01*
Y159452D01*
Y159315D01*
Y159178D01*
Y159040D01*
X293606D01*
Y158903D01*
Y158766D01*
Y158629D01*
Y158491D01*
Y158354D01*
Y158217D01*
Y158079D01*
Y157942D01*
Y157805D01*
Y157667D01*
Y157530D01*
Y157393D01*
Y157255D01*
Y157118D01*
X293468D01*
Y156981D01*
Y156843D01*
Y156706D01*
X293606D01*
Y156569D01*
X293468D01*
Y156432D01*
Y156294D01*
Y156157D01*
Y156019D01*
Y155882D01*
Y155745D01*
Y155608D01*
Y155470D01*
Y155333D01*
Y155196D01*
Y155058D01*
Y154921D01*
X295116D01*
Y155058D01*
Y155196D01*
Y155333D01*
Y155470D01*
Y155608D01*
Y155745D01*
Y155882D01*
Y156019D01*
Y156157D01*
Y156294D01*
Y156432D01*
X295253D01*
Y156569D01*
Y156706D01*
Y156843D01*
Y156981D01*
Y157118D01*
Y157255D01*
Y157393D01*
Y157530D01*
Y157667D01*
Y157805D01*
Y157942D01*
Y158079D01*
Y158217D01*
Y158354D01*
Y158491D01*
Y158629D01*
Y158766D01*
X295391D01*
Y158903D01*
Y159040D01*
Y159178D01*
Y159315D01*
Y159452D01*
Y159590D01*
Y159727D01*
Y159864D01*
Y160002D01*
X295528D01*
Y160139D01*
Y160276D01*
Y160414D01*
Y160551D01*
Y160688D01*
Y160826D01*
Y160963D01*
Y161100D01*
Y161238D01*
X295665D01*
Y161375D01*
Y161512D01*
Y161649D01*
Y161787D01*
Y161924D01*
Y162062D01*
Y162199D01*
X295803D01*
Y162336D01*
Y162473D01*
Y162611D01*
Y162748D01*
Y162885D01*
Y163023D01*
X295940D01*
Y163160D01*
Y163297D01*
Y163435D01*
Y163572D01*
Y163709D01*
X296077D01*
Y163847D01*
Y163984D01*
Y164121D01*
Y164259D01*
Y164396D01*
Y164533D01*
X296215D01*
Y164671D01*
Y164808D01*
Y164945D01*
Y165082D01*
X296352D01*
Y165220D01*
Y165357D01*
Y165494D01*
Y165632D01*
Y165769D01*
X296489D01*
Y165906D01*
Y166044D01*
Y166181D01*
Y166318D01*
X296627D01*
Y166456D01*
Y166593D01*
Y166730D01*
Y166868D01*
X296764D01*
Y167005D01*
Y167142D01*
Y167280D01*
Y167417D01*
X296901D01*
Y167554D01*
Y167691D01*
Y167829D01*
Y167966D01*
X297038D01*
Y168104D01*
Y168241D01*
Y168378D01*
X297176D01*
Y168515D01*
Y168653D01*
Y168790D01*
Y168927D01*
X297313D01*
Y169065D01*
Y169202D01*
Y169339D01*
X297451D01*
Y169477D01*
Y169614D01*
Y169751D01*
X297588D01*
Y169889D01*
Y170026D01*
Y170163D01*
Y170301D01*
X297725D01*
Y170438D01*
Y170575D01*
Y170713D01*
X297862D01*
Y170850D01*
Y170987D01*
Y171124D01*
X298000D01*
Y171262D01*
Y171399D01*
X298137D01*
Y171536D01*
Y171674D01*
Y171811D01*
X298274D01*
Y171948D01*
Y172086D01*
Y172223D01*
X298412D01*
Y172360D01*
Y172498D01*
Y172635D01*
X298549D01*
Y172772D01*
Y172910D01*
X298686D01*
Y173047D01*
Y173184D01*
Y173321D01*
X298824D01*
Y173459D01*
Y173596D01*
X298961D01*
Y173734D01*
Y173871D01*
Y174008D01*
X299098D01*
Y174145D01*
Y174283D01*
X299236D01*
Y174420D01*
Y174557D01*
X299373D01*
Y174695D01*
Y174832D01*
Y174969D01*
X299510D01*
Y175107D01*
Y175244D01*
X299648D01*
Y175381D01*
Y175519D01*
X299785D01*
Y175656D01*
Y175793D01*
X299922D01*
Y175931D01*
Y176068D01*
X300060D01*
Y176205D01*
Y176343D01*
X300197D01*
Y176480D01*
Y176617D01*
Y176754D01*
X300334D01*
Y176892D01*
Y177029D01*
X300471D01*
Y177166D01*
Y177304D01*
X300609D01*
Y177441D01*
Y177578D01*
X300746D01*
Y177716D01*
Y177853D01*
X300883D01*
Y177990D01*
X301021D01*
Y178128D01*
Y178265D01*
X301158D01*
Y178402D01*
Y178540D01*
X301295D01*
Y178677D01*
Y178814D01*
X301433D01*
Y178952D01*
Y179089D01*
X301570D01*
Y179226D01*
Y179363D01*
X301707D01*
Y179501D01*
X301845D01*
Y179638D01*
Y179776D01*
X301982D01*
Y179913D01*
Y180050D01*
X302119D01*
Y180187D01*
Y180325D01*
X302257D01*
Y180462D01*
X302394D01*
Y180599D01*
Y180737D01*
X302531D01*
Y180874D01*
Y181011D01*
X302668D01*
Y181149D01*
X302806D01*
Y181286D01*
Y181423D01*
X302943D01*
Y181561D01*
Y181698D01*
X303081D01*
Y181835D01*
X303218D01*
Y181973D01*
Y182110D01*
X303355D01*
Y182247D01*
X303492D01*
Y182384D01*
Y182522D01*
X303630D01*
Y182659D01*
X303767D01*
Y182796D01*
Y182934D01*
X303904D01*
Y183071D01*
X304042D01*
Y183208D01*
Y183346D01*
X304179D01*
Y183483D01*
X304316D01*
Y183620D01*
Y183758D01*
X304454D01*
Y183895D01*
X304591D01*
Y184032D01*
X304728D01*
Y184170D01*
Y184307D01*
X304866D01*
Y184444D01*
X305003D01*
Y184582D01*
Y184719D01*
X305140D01*
Y184856D01*
X305278D01*
Y184993D01*
X305415D01*
Y185131D01*
Y185268D01*
X305552D01*
Y185406D01*
X305690D01*
Y185543D01*
X305827D01*
Y185680D01*
Y185817D01*
X305964D01*
Y185955D01*
X306101D01*
Y186092D01*
X306239D01*
Y186229D01*
X306376D01*
Y186367D01*
Y186504D01*
X306513D01*
Y186641D01*
X306651D01*
Y186779D01*
X306788D01*
Y186916D01*
X306925D01*
Y187053D01*
Y187191D01*
X307063D01*
Y187328D01*
X307200D01*
Y187465D01*
X307337D01*
Y187603D01*
X307475D01*
Y187740D01*
X307612D01*
Y187877D01*
X307749D01*
Y188015D01*
Y188152D01*
X307887D01*
Y188289D01*
X308024D01*
Y188426D01*
X308161D01*
Y188564D01*
X308298D01*
Y188701D01*
X308436D01*
Y188838D01*
X308573D01*
Y188976D01*
X308710D01*
Y189113D01*
X308848D01*
Y189250D01*
X308985D01*
Y189388D01*
Y189525D01*
X309122D01*
Y189662D01*
X309260D01*
Y189800D01*
X309397D01*
Y189937D01*
X309534D01*
Y190074D01*
X309672D01*
Y190212D01*
X309809D01*
Y190349D01*
X309946D01*
Y190486D01*
X310084D01*
Y190623D01*
X310221D01*
Y190761D01*
X310358D01*
Y190898D01*
X310496D01*
Y191035D01*
X310633D01*
Y191173D01*
X310770D01*
Y191310D01*
X310908D01*
Y191447D01*
X311045D01*
Y191585D01*
X311182D01*
Y191722D01*
X311320D01*
Y191859D01*
X311594D01*
Y191997D01*
X311731D01*
Y192134D01*
X311869D01*
Y192271D01*
X312006D01*
Y192409D01*
X312143D01*
Y192546D01*
X312281D01*
Y192683D01*
X312418D01*
Y192821D01*
X312555D01*
Y192958D01*
X312693D01*
Y193095D01*
X312967D01*
Y193233D01*
X313105D01*
Y193370D01*
X313242D01*
Y193507D01*
X313379D01*
Y193645D01*
X313517D01*
Y193782D01*
X313654D01*
Y193919D01*
X313929D01*
Y194056D01*
X314066D01*
Y194194D01*
X314203D01*
Y194331D01*
X314340D01*
Y194468D01*
X314615D01*
Y194606D01*
X314753D01*
Y194743D01*
X314890D01*
Y194880D01*
X315027D01*
Y195018D01*
X315302D01*
Y195155D01*
X315439D01*
Y195292D01*
X315576D01*
Y195430D01*
X315851D01*
Y195567D01*
X315988D01*
Y195704D01*
X316126D01*
Y195842D01*
X316400D01*
Y195979D01*
X316538D01*
Y196116D01*
X316812D01*
Y196254D01*
X316950D01*
Y196391D01*
X317087D01*
Y196528D01*
X317362D01*
Y196665D01*
X317499D01*
Y196803D01*
X317773D01*
Y196940D01*
X317911D01*
Y197078D01*
X318185D01*
Y197215D01*
X318323D01*
Y197352D01*
X318597D01*
Y197489D01*
X318735D01*
Y197627D01*
X319009D01*
Y197764D01*
X319147D01*
Y197901D01*
X319421D01*
Y198039D01*
X319696D01*
Y198176D01*
X319833D01*
Y198313D01*
X320108D01*
Y198451D01*
X320382D01*
Y198588D01*
X320520D01*
Y198725D01*
X320794D01*
Y198863D01*
X321069D01*
Y199000D01*
X321344D01*
Y199137D01*
X321481D01*
Y199275D01*
X321756D01*
Y199412D01*
X322030D01*
Y199549D01*
X322305D01*
Y199687D01*
X322580D01*
Y199824D01*
X322854D01*
Y199961D01*
X323129D01*
Y200098D01*
X323404D01*
Y200236D01*
X323678D01*
Y200373D01*
X323815D01*
Y200510D01*
X324090D01*
Y200648D01*
X324502D01*
Y200785D01*
X324777D01*
Y200922D01*
X325051D01*
Y201060D01*
X325326D01*
Y201197D01*
X325601D01*
Y201334D01*
X326012D01*
Y201472D01*
X326287D01*
Y201609D01*
X326562D01*
Y201746D01*
X326974D01*
Y201884D01*
X327248D01*
Y202021D01*
X327660D01*
Y202158D01*
X327935D01*
Y202295D01*
X328347D01*
Y202433D01*
X328621D01*
Y202570D01*
X329034D01*
Y202708D01*
X329445D01*
Y202845D01*
X329857D01*
Y202982D01*
X330269D01*
Y203119D01*
X330681D01*
Y203257D01*
X331093D01*
Y203394D01*
X331505D01*
Y203531D01*
X331917D01*
Y203669D01*
X332466D01*
Y203806D01*
X332878D01*
Y203943D01*
X333428D01*
Y204081D01*
X333977D01*
Y204218D01*
X334526D01*
Y204355D01*
X335075D01*
Y204493D01*
X335762D01*
Y204630D01*
X336449D01*
Y204767D01*
X337135D01*
Y204905D01*
X337959D01*
Y205042D01*
X338783D01*
Y205179D01*
X339607D01*
Y205317D01*
X340843D01*
Y205454D01*
X342353D01*
Y205591D01*
X344550D01*
Y205728D01*
X344688D01*
Y205591D01*
X344825D01*
Y205728D01*
X348258D01*
Y205591D01*
X350730D01*
Y205454D01*
X352240D01*
Y205317D01*
X353339D01*
Y205179D01*
X354300D01*
Y205042D01*
X355124D01*
Y204905D01*
X356085D01*
Y204767D01*
X356634D01*
Y204630D01*
X357321D01*
Y204493D01*
X358008D01*
Y204355D01*
X358557D01*
Y204218D01*
X359106D01*
Y204081D01*
X359655D01*
Y203943D01*
X360205D01*
Y203806D01*
X360616D01*
Y203669D01*
X361166D01*
Y203531D01*
X361578D01*
Y203394D01*
X361990D01*
Y203257D01*
X362402D01*
Y203119D01*
X362951D01*
Y202982D01*
X363226D01*
Y202845D01*
X363638D01*
Y202708D01*
X364049D01*
Y202570D01*
X364461D01*
Y202433D01*
X364736D01*
Y202295D01*
X365148D01*
Y202158D01*
X365560D01*
Y202021D01*
X365835D01*
Y201884D01*
X366246D01*
Y201746D01*
X366521D01*
Y201609D01*
X366796D01*
Y201472D01*
X367208D01*
Y201334D01*
X367482D01*
Y201197D01*
X367757D01*
Y201060D01*
X368032D01*
Y200922D01*
X368306D01*
Y200785D01*
X368581D01*
Y200648D01*
X368993D01*
Y200510D01*
X369268D01*
Y200373D01*
X369542D01*
Y200236D01*
X369817D01*
Y200098D01*
X370091D01*
Y199961D01*
X370229D01*
Y199824D01*
X370503D01*
Y199687D01*
X370778D01*
Y199549D01*
X371053D01*
Y199412D01*
X371327D01*
Y199275D01*
X371602D01*
Y199137D01*
X371876D01*
Y199000D01*
X372014D01*
Y198863D01*
X372289D01*
Y198725D01*
X372563D01*
Y198588D01*
X372700D01*
Y198451D01*
X372975D01*
Y198313D01*
X373250D01*
Y198176D01*
X373387D01*
Y198039D01*
X373662D01*
Y197901D01*
X373936D01*
Y197764D01*
X374074D01*
Y197627D01*
X374348D01*
Y197489D01*
X374486D01*
Y197352D01*
X374760D01*
Y197215D01*
X374897D01*
Y197078D01*
X375172D01*
Y196940D01*
X375309D01*
Y196803D01*
X375584D01*
Y196665D01*
X375721D01*
Y196528D01*
X375996D01*
Y196391D01*
X376133D01*
Y196254D01*
X376408D01*
Y196116D01*
X376545D01*
Y195979D01*
X376683D01*
Y195842D01*
X376957D01*
Y195704D01*
X377095D01*
Y195567D01*
X377232D01*
Y195430D01*
X377507D01*
Y195292D01*
X377644D01*
Y195155D01*
X377781D01*
Y195018D01*
X378056D01*
Y194880D01*
X378193D01*
Y194743D01*
X378330D01*
Y194606D01*
X378468D01*
Y194468D01*
X378742D01*
Y194331D01*
X378880D01*
Y194194D01*
X379017D01*
Y194056D01*
X379154D01*
Y193919D01*
X379429D01*
Y193782D01*
X379566D01*
Y193645D01*
X379704D01*
Y193507D01*
X379841D01*
Y193370D01*
X379978D01*
Y193233D01*
X380253D01*
Y193095D01*
X380390D01*
Y192958D01*
X380528D01*
Y192821D01*
X380665D01*
Y192683D01*
X380802D01*
Y192546D01*
X380939D01*
Y192409D01*
X381077D01*
Y192271D01*
X381214D01*
Y192134D01*
X381352D01*
Y191997D01*
X381626D01*
Y191859D01*
X381763D01*
Y191722D01*
X381901D01*
Y191585D01*
X382038D01*
Y191447D01*
X382175D01*
Y191310D01*
X382313D01*
Y191173D01*
X382450D01*
Y191035D01*
X382587D01*
Y190898D01*
X382725D01*
Y190761D01*
X382862D01*
Y190623D01*
X382999D01*
Y190486D01*
X383137D01*
Y190349D01*
X383274D01*
Y190212D01*
X383411D01*
Y190074D01*
X383549D01*
Y189937D01*
X383686D01*
Y189800D01*
X383823D01*
Y189662D01*
X383960D01*
Y189525D01*
X384098D01*
Y189388D01*
X384235D01*
Y189250D01*
X384372D01*
Y189113D01*
Y188976D01*
X384510D01*
Y188838D01*
X384647D01*
Y188701D01*
X384784D01*
Y188564D01*
X384922D01*
Y188426D01*
X385059D01*
Y188289D01*
X385196D01*
Y188152D01*
X385334D01*
Y188015D01*
X385471D01*
Y187877D01*
Y187740D01*
X385608D01*
Y187603D01*
X385746D01*
Y187465D01*
X387943D01*
Y187603D01*
X387805D01*
Y187740D01*
X387668D01*
Y187877D01*
X387531D01*
Y188015D01*
Y188152D01*
X387393D01*
Y188289D01*
X387256D01*
Y188426D01*
X387119D01*
Y188564D01*
X386982D01*
Y188701D01*
X386844D01*
Y188838D01*
Y188976D01*
X386707D01*
Y189113D01*
X386570D01*
Y189250D01*
X386432D01*
Y189388D01*
X386295D01*
Y189525D01*
X386158D01*
Y189662D01*
X386020D01*
Y189800D01*
X385883D01*
Y189937D01*
X385746D01*
Y190074D01*
Y190212D01*
X385608D01*
Y190349D01*
X385471D01*
Y190486D01*
X385334D01*
Y190623D01*
X385196D01*
Y190761D01*
X385059D01*
Y190898D01*
X384922D01*
Y191035D01*
X384784D01*
Y191173D01*
X384647D01*
Y191310D01*
X384510D01*
Y191447D01*
X384372D01*
Y191585D01*
X384235D01*
Y191722D01*
X384098D01*
Y191859D01*
X383960D01*
Y191997D01*
X383823D01*
Y192134D01*
X383686D01*
Y192271D01*
X383549D01*
Y192409D01*
X383411D01*
Y192546D01*
X383274D01*
Y192683D01*
X383137D01*
Y192821D01*
X382999D01*
Y192958D01*
X382862D01*
Y193095D01*
X382725D01*
Y193233D01*
X382587D01*
Y193370D01*
X382450D01*
Y193507D01*
X382175D01*
Y193645D01*
X382038D01*
Y193782D01*
X381901D01*
Y193919D01*
X381763D01*
Y194056D01*
X381626D01*
Y194194D01*
X381489D01*
Y194331D01*
X381352D01*
Y194468D01*
X381214D01*
Y194606D01*
X380939D01*
Y194743D01*
X380802D01*
Y194880D01*
X380665D01*
Y195018D01*
X380528D01*
Y195155D01*
X380390D01*
Y195292D01*
X380116D01*
Y195430D01*
X379978D01*
Y195567D01*
X379841D01*
Y195704D01*
X379704D01*
Y195842D01*
X379429D01*
Y195979D01*
X379292D01*
Y196116D01*
X379154D01*
Y196254D01*
X379017D01*
Y196391D01*
X378742D01*
Y196528D01*
X378605D01*
Y196665D01*
X378468D01*
Y196803D01*
X378193D01*
Y196940D01*
X378056D01*
Y197078D01*
X377919D01*
Y197215D01*
X377644D01*
Y197352D01*
X377507D01*
Y197489D01*
X377232D01*
Y197627D01*
X377095D01*
Y197764D01*
X376957D01*
Y197901D01*
X376683D01*
Y198039D01*
X376545D01*
Y198176D01*
X376271D01*
Y198313D01*
X376133D01*
Y198451D01*
X375859D01*
Y198588D01*
X375721D01*
Y198725D01*
X375447D01*
Y198863D01*
X375309D01*
Y199000D01*
X375035D01*
Y199137D01*
X374897D01*
Y199275D01*
X374623D01*
Y199412D01*
X374348D01*
Y199549D01*
X374211D01*
Y199687D01*
X373936D01*
Y199824D01*
X373662D01*
Y199961D01*
X373524D01*
Y200098D01*
X373250D01*
Y200236D01*
X372975D01*
Y200373D01*
X372838D01*
Y200510D01*
X372563D01*
Y200648D01*
X372289D01*
Y200785D01*
X372014D01*
Y200922D01*
X371739D01*
Y201060D01*
X371602D01*
Y201197D01*
X371327D01*
Y201334D01*
X371053D01*
Y201472D01*
X370778D01*
Y201609D01*
X370503D01*
Y201746D01*
X370229D01*
Y201884D01*
X369954D01*
Y202021D01*
X369679D01*
Y202158D01*
X369405D01*
Y202295D01*
X369130D01*
Y202433D01*
X368718D01*
Y202570D01*
X368444D01*
Y202708D01*
X368169D01*
Y202845D01*
X367894D01*
Y202982D01*
X367482D01*
Y203119D01*
X367208D01*
Y203257D01*
X366933D01*
Y203394D01*
X366521D01*
Y203531D01*
X366246D01*
Y203669D01*
X365835D01*
Y203806D01*
X365560D01*
Y203943D01*
X365148D01*
Y204081D01*
X364736D01*
Y204218D01*
X364324D01*
Y204355D01*
X364049D01*
Y204493D01*
X363638D01*
Y204630D01*
X363226D01*
Y204767D01*
X362814D01*
Y204905D01*
X362264D01*
Y205042D01*
X361852D01*
Y205179D01*
X361440D01*
Y205317D01*
X360891D01*
Y205454D01*
X360479D01*
Y205591D01*
X359930D01*
Y205728D01*
X359381D01*
Y205866D01*
X358831D01*
Y206003D01*
X358282D01*
Y206140D01*
X357595D01*
Y206278D01*
X356909D01*
Y206415D01*
X356222D01*
Y206552D01*
X355398D01*
Y206690D01*
X354437D01*
Y206827D01*
X353613D01*
Y206964D01*
X352515D01*
Y207102D01*
X351142D01*
Y207239D01*
X349082D01*
Y207376D01*
D02*
G37*
G36*
X410051Y185268D02*
X388904D01*
Y185131D01*
X388767D01*
Y185268D01*
X388492D01*
Y185131D01*
X388217D01*
Y184993D01*
X388080D01*
Y184856D01*
X387943D01*
Y184719D01*
Y184582D01*
Y184444D01*
X387805D01*
Y184307D01*
Y184170D01*
Y184032D01*
Y183895D01*
Y183758D01*
Y183620D01*
Y183483D01*
Y183346D01*
Y183208D01*
Y183071D01*
Y182934D01*
Y182796D01*
Y182659D01*
Y182522D01*
Y182384D01*
Y182247D01*
Y182110D01*
Y181973D01*
Y181835D01*
Y181698D01*
Y181561D01*
Y181423D01*
Y181286D01*
Y181149D01*
Y181011D01*
Y180874D01*
Y180737D01*
Y180599D01*
Y180462D01*
Y180325D01*
Y180187D01*
Y180050D01*
Y179913D01*
Y179776D01*
Y179638D01*
Y179501D01*
Y179363D01*
Y179226D01*
Y179089D01*
Y178952D01*
Y178814D01*
Y178677D01*
X387943D01*
Y178540D01*
Y178402D01*
Y178265D01*
X388080D01*
Y178128D01*
X388217D01*
Y177990D01*
X388629D01*
Y177853D01*
X395220D01*
Y177716D01*
X395358D01*
Y177578D01*
X395495D01*
Y177441D01*
Y177304D01*
Y177166D01*
Y177029D01*
Y176892D01*
Y176754D01*
Y176617D01*
Y176480D01*
Y176343D01*
Y176205D01*
Y176068D01*
Y175931D01*
Y175793D01*
Y175656D01*
Y175519D01*
Y175381D01*
Y175244D01*
Y175107D01*
Y174969D01*
Y174832D01*
Y174695D01*
Y174557D01*
Y174420D01*
Y174283D01*
Y174145D01*
Y174008D01*
Y173871D01*
Y173734D01*
Y173596D01*
Y173459D01*
Y173321D01*
Y173184D01*
Y173047D01*
Y172910D01*
Y172772D01*
Y172635D01*
Y172498D01*
Y172360D01*
Y172223D01*
Y172086D01*
Y171948D01*
Y171811D01*
Y171674D01*
Y171536D01*
Y171399D01*
Y171262D01*
Y171124D01*
Y170987D01*
Y170850D01*
Y170713D01*
Y170575D01*
Y170438D01*
Y170301D01*
Y170163D01*
Y170026D01*
Y169889D01*
Y169751D01*
Y169614D01*
Y169477D01*
Y169339D01*
Y169202D01*
Y169065D01*
Y168927D01*
Y168790D01*
Y168653D01*
Y168515D01*
Y168378D01*
Y168241D01*
Y168104D01*
Y167966D01*
Y167829D01*
Y167691D01*
Y167554D01*
Y167417D01*
Y167280D01*
Y167142D01*
Y167005D01*
Y166868D01*
Y166730D01*
Y166593D01*
Y166456D01*
Y166318D01*
Y166181D01*
Y166044D01*
Y165906D01*
Y165769D01*
Y165632D01*
Y165494D01*
Y165357D01*
Y165220D01*
Y165082D01*
Y164945D01*
Y164808D01*
Y164671D01*
Y164533D01*
Y164396D01*
Y164259D01*
Y164121D01*
Y163984D01*
Y163847D01*
Y163709D01*
Y163572D01*
Y163435D01*
Y163297D01*
Y163160D01*
Y163023D01*
Y162885D01*
Y162748D01*
Y162611D01*
Y162473D01*
Y162336D01*
Y162199D01*
Y162062D01*
Y161924D01*
Y161787D01*
Y161649D01*
Y161512D01*
Y161375D01*
Y161238D01*
Y161100D01*
Y160963D01*
Y160826D01*
Y160688D01*
Y160551D01*
Y160414D01*
Y160276D01*
Y160139D01*
Y160002D01*
Y159864D01*
Y159727D01*
Y159590D01*
Y159452D01*
Y159315D01*
Y159178D01*
Y159040D01*
Y158903D01*
Y158766D01*
Y158629D01*
Y158491D01*
Y158354D01*
Y158217D01*
Y158079D01*
Y157942D01*
Y157805D01*
Y157667D01*
Y157530D01*
Y157393D01*
Y157255D01*
Y157118D01*
Y156981D01*
Y156843D01*
Y156706D01*
Y156569D01*
Y156432D01*
Y156294D01*
Y156157D01*
Y156019D01*
X395633D01*
Y155882D01*
Y155745D01*
Y155608D01*
X395770D01*
Y155470D01*
X395907D01*
Y155333D01*
X402636D01*
Y155470D01*
X402773D01*
Y155608D01*
X402910D01*
Y155745D01*
X403048D01*
Y155882D01*
Y156019D01*
Y156157D01*
Y156294D01*
Y156432D01*
Y156569D01*
Y156706D01*
Y156843D01*
Y156981D01*
Y157118D01*
Y157255D01*
Y157393D01*
Y157530D01*
Y157667D01*
Y157805D01*
Y157942D01*
Y158079D01*
Y158217D01*
Y158354D01*
Y158491D01*
Y158629D01*
Y158766D01*
Y158903D01*
Y159040D01*
Y159178D01*
Y159315D01*
Y159452D01*
Y159590D01*
Y159727D01*
Y159864D01*
Y160002D01*
Y160139D01*
Y160276D01*
Y160414D01*
Y160551D01*
Y160688D01*
Y160826D01*
Y160963D01*
Y161100D01*
Y161238D01*
Y161375D01*
Y161512D01*
Y161649D01*
Y161787D01*
Y161924D01*
Y162062D01*
Y162199D01*
Y162336D01*
Y162473D01*
Y162611D01*
Y162748D01*
Y162885D01*
Y163023D01*
Y163160D01*
Y163297D01*
Y163435D01*
Y163572D01*
Y163709D01*
Y163847D01*
Y163984D01*
Y164121D01*
Y164259D01*
Y164396D01*
Y164533D01*
Y164671D01*
Y164808D01*
Y164945D01*
Y165082D01*
Y165220D01*
Y165357D01*
Y165494D01*
Y165632D01*
Y165769D01*
Y165906D01*
Y166044D01*
Y166181D01*
Y166318D01*
Y166456D01*
Y166593D01*
Y166730D01*
Y166868D01*
Y167005D01*
Y167142D01*
Y167280D01*
Y167417D01*
Y167554D01*
Y167691D01*
Y167829D01*
Y167966D01*
Y168104D01*
Y168241D01*
Y168378D01*
Y168515D01*
Y168653D01*
Y168790D01*
Y168927D01*
Y169065D01*
Y169202D01*
Y169339D01*
Y169477D01*
Y169614D01*
Y169751D01*
Y169889D01*
Y170026D01*
Y170163D01*
Y170301D01*
Y170438D01*
Y170575D01*
Y170713D01*
Y170850D01*
Y170987D01*
Y171124D01*
Y171262D01*
Y171399D01*
Y171536D01*
Y171674D01*
Y171811D01*
Y171948D01*
Y172086D01*
Y172223D01*
Y172360D01*
Y172498D01*
Y172635D01*
Y172772D01*
Y172910D01*
Y173047D01*
Y173184D01*
Y173321D01*
Y173459D01*
Y173596D01*
Y173734D01*
Y173871D01*
Y174008D01*
Y174145D01*
Y174283D01*
Y174420D01*
Y174557D01*
Y174695D01*
Y174832D01*
Y174969D01*
Y175107D01*
Y175244D01*
Y175381D01*
Y175519D01*
Y175656D01*
Y175793D01*
Y175931D01*
Y176068D01*
Y176205D01*
Y176343D01*
Y176480D01*
Y176617D01*
Y176754D01*
Y176892D01*
Y177029D01*
Y177166D01*
Y177304D01*
X403185D01*
Y177441D01*
Y177578D01*
X403322D01*
Y177716D01*
X403460D01*
Y177853D01*
X410051D01*
Y177990D01*
X410325D01*
Y178128D01*
X410463D01*
Y178265D01*
X410600D01*
Y178402D01*
X410737D01*
Y178540D01*
Y178677D01*
Y178814D01*
Y178952D01*
Y179089D01*
Y179226D01*
Y179363D01*
Y179501D01*
Y179638D01*
Y179776D01*
Y179913D01*
Y180050D01*
Y180187D01*
Y180325D01*
Y180462D01*
Y180599D01*
Y180737D01*
Y180874D01*
Y181011D01*
Y181149D01*
Y181286D01*
Y181423D01*
Y181561D01*
Y181698D01*
Y181835D01*
Y181973D01*
Y182110D01*
Y182247D01*
Y182384D01*
Y182522D01*
Y182659D01*
Y182796D01*
Y182934D01*
Y183071D01*
Y183208D01*
Y183346D01*
Y183483D01*
Y183620D01*
Y183758D01*
Y183895D01*
Y184032D01*
Y184170D01*
Y184307D01*
Y184444D01*
Y184582D01*
Y184719D01*
X410600D01*
Y184856D01*
Y184993D01*
X410463D01*
Y185131D01*
X410051D01*
Y185268D01*
D02*
G37*
G36*
X334801D02*
X318735D01*
Y185131D01*
X318597D01*
Y185268D01*
X318185D01*
Y185131D01*
X317911D01*
Y184993D01*
X317773D01*
Y184856D01*
X317636D01*
Y184719D01*
Y184582D01*
X317499D01*
Y184444D01*
Y184307D01*
Y184170D01*
Y184032D01*
Y183895D01*
Y183758D01*
Y183620D01*
Y183483D01*
Y183346D01*
Y183208D01*
Y183071D01*
Y182934D01*
Y182796D01*
Y182659D01*
Y182522D01*
Y182384D01*
Y182247D01*
Y182110D01*
Y181973D01*
Y181835D01*
Y181698D01*
Y181561D01*
Y181423D01*
Y181286D01*
Y181149D01*
Y181011D01*
Y180874D01*
Y180737D01*
Y180599D01*
Y180462D01*
Y180325D01*
Y180187D01*
Y180050D01*
Y179913D01*
Y179776D01*
Y179638D01*
Y179501D01*
Y179363D01*
Y179226D01*
Y179089D01*
Y178952D01*
Y178814D01*
Y178677D01*
X317636D01*
Y178540D01*
X317773D01*
Y178402D01*
X317911D01*
Y178265D01*
X332741D01*
Y178128D01*
X332878D01*
Y177990D01*
Y177853D01*
Y177716D01*
Y177578D01*
Y177441D01*
Y177304D01*
Y177166D01*
Y177029D01*
Y176892D01*
Y176754D01*
Y176617D01*
Y176480D01*
Y176343D01*
Y176205D01*
Y176068D01*
Y175931D01*
Y175793D01*
Y175656D01*
Y175519D01*
Y175381D01*
Y175244D01*
Y175107D01*
Y174969D01*
Y174832D01*
Y174695D01*
Y174557D01*
Y174420D01*
Y174283D01*
Y174145D01*
Y174008D01*
Y173871D01*
Y173734D01*
Y173596D01*
Y173459D01*
Y173321D01*
X332741D01*
Y173184D01*
X320108D01*
Y173047D01*
X319833D01*
Y172910D01*
Y172772D01*
X319696D01*
Y172635D01*
Y172498D01*
Y172360D01*
Y172223D01*
Y172086D01*
Y171948D01*
Y171811D01*
Y171674D01*
Y171536D01*
Y171399D01*
Y171262D01*
Y171124D01*
Y170987D01*
Y170850D01*
Y170713D01*
Y170575D01*
Y170438D01*
Y170301D01*
Y170163D01*
Y170026D01*
Y169889D01*
Y169751D01*
Y169614D01*
Y169477D01*
Y169339D01*
Y169202D01*
Y169065D01*
Y168927D01*
Y168790D01*
Y168653D01*
Y168515D01*
Y168378D01*
Y168241D01*
Y168104D01*
Y167966D01*
Y167829D01*
Y167691D01*
X319833D01*
Y167554D01*
Y167417D01*
X320108D01*
Y167280D01*
X332741D01*
Y167142D01*
X332878D01*
Y167005D01*
Y166868D01*
Y166730D01*
Y166593D01*
Y166456D01*
Y166318D01*
Y166181D01*
Y166044D01*
Y165906D01*
Y165769D01*
Y165632D01*
Y165494D01*
Y165357D01*
Y165220D01*
Y165082D01*
Y164945D01*
Y164808D01*
Y164671D01*
Y164533D01*
Y164396D01*
Y164259D01*
Y164121D01*
Y163984D01*
Y163847D01*
Y163709D01*
Y163572D01*
Y163435D01*
Y163297D01*
Y163160D01*
Y163023D01*
Y162885D01*
Y162748D01*
Y162611D01*
Y162473D01*
X332741D01*
Y162336D01*
X318048D01*
Y162199D01*
X317773D01*
Y162062D01*
X317636D01*
Y161924D01*
Y161787D01*
X317499D01*
Y161649D01*
Y161512D01*
Y161375D01*
Y161238D01*
Y161100D01*
Y160963D01*
Y160826D01*
Y160688D01*
Y160551D01*
Y160414D01*
Y160276D01*
Y160139D01*
Y160002D01*
Y159864D01*
Y159727D01*
Y159590D01*
Y159452D01*
Y159315D01*
Y159178D01*
Y159040D01*
Y158903D01*
Y158766D01*
Y158629D01*
Y158491D01*
Y158354D01*
Y158217D01*
Y158079D01*
Y157942D01*
Y157805D01*
Y157667D01*
Y157530D01*
Y157393D01*
Y157255D01*
Y157118D01*
Y156981D01*
Y156843D01*
Y156706D01*
Y156569D01*
Y156432D01*
Y156294D01*
Y156157D01*
Y156019D01*
Y155882D01*
X317636D01*
Y155745D01*
Y155608D01*
X317773D01*
Y155470D01*
X317911D01*
Y155333D01*
X335350D01*
Y155470D01*
X335899D01*
Y155608D01*
X336174D01*
Y155745D01*
X336311D01*
Y155882D01*
X336449D01*
Y156019D01*
X336586D01*
Y156157D01*
X336723D01*
Y156294D01*
X336861D01*
Y156432D01*
X336998D01*
Y156569D01*
X337135D01*
Y156706D01*
X337272D01*
Y156843D01*
X337410D01*
Y156981D01*
X337547D01*
Y157118D01*
X337685D01*
Y157255D01*
X337822D01*
Y157393D01*
X337959D01*
Y157530D01*
X338097D01*
Y157667D01*
X338234D01*
Y157805D01*
X338371D01*
Y157942D01*
X338508D01*
Y158079D01*
X338646D01*
Y158217D01*
X338783D01*
Y158354D01*
X338920D01*
Y158491D01*
X339058D01*
Y158629D01*
X339195D01*
Y158766D01*
X339332D01*
Y158903D01*
X339470D01*
Y159040D01*
X339607D01*
Y159178D01*
X339744D01*
Y159315D01*
X339882D01*
Y159452D01*
X340019D01*
Y159590D01*
Y159727D01*
X340156D01*
Y159864D01*
Y160002D01*
X340294D01*
Y160139D01*
Y160276D01*
Y160414D01*
Y160551D01*
Y160688D01*
X340431D01*
Y160826D01*
Y160963D01*
Y161100D01*
Y161238D01*
Y161375D01*
Y161512D01*
Y161649D01*
Y161787D01*
Y161924D01*
Y162062D01*
Y162199D01*
Y162336D01*
Y162473D01*
Y162611D01*
Y162748D01*
Y162885D01*
Y163023D01*
Y163160D01*
Y163297D01*
Y163435D01*
Y163572D01*
Y163709D01*
Y163847D01*
Y163984D01*
Y164121D01*
Y164259D01*
Y164396D01*
Y164533D01*
Y164671D01*
Y164808D01*
Y164945D01*
Y165082D01*
Y165220D01*
Y165357D01*
Y165494D01*
Y165632D01*
Y165769D01*
Y165906D01*
Y166044D01*
Y166181D01*
Y166318D01*
Y166456D01*
Y166593D01*
Y166730D01*
Y166868D01*
Y167005D01*
Y167142D01*
Y167280D01*
Y167417D01*
Y167554D01*
Y167691D01*
Y167829D01*
Y167966D01*
Y168104D01*
Y168241D01*
Y168378D01*
Y168515D01*
Y168653D01*
Y168790D01*
Y168927D01*
Y169065D01*
Y169202D01*
Y169339D01*
Y169477D01*
Y169614D01*
Y169751D01*
Y169889D01*
Y170026D01*
Y170163D01*
Y170301D01*
Y170438D01*
Y170575D01*
Y170713D01*
Y170850D01*
Y170987D01*
Y171124D01*
Y171262D01*
Y171399D01*
Y171536D01*
Y171674D01*
Y171811D01*
Y171948D01*
Y172086D01*
Y172223D01*
Y172360D01*
Y172498D01*
Y172635D01*
Y172772D01*
Y172910D01*
Y173047D01*
Y173184D01*
Y173321D01*
Y173459D01*
Y173596D01*
Y173734D01*
Y173871D01*
Y174008D01*
Y174145D01*
Y174283D01*
Y174420D01*
Y174557D01*
Y174695D01*
Y174832D01*
Y174969D01*
Y175107D01*
Y175244D01*
Y175381D01*
Y175519D01*
Y175656D01*
Y175793D01*
Y175931D01*
Y176068D01*
Y176205D01*
Y176343D01*
Y176480D01*
Y176617D01*
Y176754D01*
Y176892D01*
Y177029D01*
Y177166D01*
Y177304D01*
Y177441D01*
Y177578D01*
Y177716D01*
Y177853D01*
Y177990D01*
Y178128D01*
Y178265D01*
Y178402D01*
Y178540D01*
Y178677D01*
Y178814D01*
Y178952D01*
Y179089D01*
Y179226D01*
Y179363D01*
Y179501D01*
Y179638D01*
Y179776D01*
X340294D01*
Y179913D01*
Y180050D01*
Y180187D01*
Y180325D01*
Y180462D01*
X340156D01*
Y180599D01*
Y180737D01*
Y180874D01*
X340019D01*
Y181011D01*
X339882D01*
Y181149D01*
X339744D01*
Y181286D01*
X339607D01*
Y181423D01*
X339470D01*
Y181561D01*
X339332D01*
Y181698D01*
X339195D01*
Y181835D01*
X339058D01*
Y181973D01*
X338920D01*
Y182110D01*
X338783D01*
Y182247D01*
X338646D01*
Y182384D01*
X338508D01*
Y182522D01*
X338371D01*
Y182659D01*
X338234D01*
Y182796D01*
X338097D01*
Y182934D01*
X337959D01*
Y183071D01*
X337822D01*
Y183208D01*
X337685D01*
Y183346D01*
X337547D01*
Y183483D01*
X337410D01*
Y183620D01*
X337272D01*
Y183758D01*
X337135D01*
Y183895D01*
X336998D01*
Y184032D01*
X336861D01*
Y184170D01*
X336723D01*
Y184307D01*
X336586D01*
Y184444D01*
X336449D01*
Y184582D01*
X336311D01*
Y184719D01*
X336174D01*
Y184856D01*
X335899D01*
Y184993D01*
X335487D01*
Y185131D01*
X334801D01*
Y185268D01*
D02*
G37*
G36*
X385471D02*
X379154D01*
Y185131D01*
X378880D01*
Y184993D01*
X378742D01*
Y184856D01*
X378605D01*
Y184719D01*
Y184582D01*
Y184444D01*
Y184307D01*
Y184170D01*
Y184032D01*
Y183895D01*
Y183758D01*
Y183620D01*
Y183483D01*
Y183346D01*
Y183208D01*
Y183071D01*
Y182934D01*
Y182796D01*
Y182659D01*
Y182522D01*
Y182384D01*
Y182247D01*
Y182110D01*
Y181973D01*
Y181835D01*
Y181698D01*
Y181561D01*
Y181423D01*
Y181286D01*
Y181149D01*
Y181011D01*
Y180874D01*
Y180737D01*
Y180599D01*
Y180462D01*
Y180325D01*
Y180187D01*
Y180050D01*
Y179913D01*
Y179776D01*
Y179638D01*
Y179501D01*
Y179363D01*
Y179226D01*
Y179089D01*
Y178952D01*
Y178814D01*
Y178677D01*
Y178540D01*
Y178402D01*
Y178265D01*
Y178128D01*
Y177990D01*
Y177853D01*
Y177716D01*
Y177578D01*
Y177441D01*
Y177304D01*
Y177166D01*
Y177029D01*
Y176892D01*
Y176754D01*
Y176617D01*
Y176480D01*
Y176343D01*
Y176205D01*
Y176068D01*
Y175931D01*
Y175793D01*
Y175656D01*
Y175519D01*
Y175381D01*
Y175244D01*
Y175107D01*
Y174969D01*
Y174832D01*
Y174695D01*
Y174557D01*
Y174420D01*
Y174283D01*
Y174145D01*
Y174008D01*
Y173871D01*
Y173734D01*
Y173596D01*
Y173459D01*
Y173321D01*
Y173184D01*
Y173047D01*
Y172910D01*
Y172772D01*
Y172635D01*
Y172498D01*
Y172360D01*
Y172223D01*
Y172086D01*
Y171948D01*
Y171811D01*
Y171674D01*
Y171536D01*
Y171399D01*
Y171262D01*
Y171124D01*
Y170987D01*
Y170850D01*
Y170713D01*
Y170575D01*
Y170438D01*
Y170301D01*
Y170163D01*
Y170026D01*
Y169889D01*
Y169751D01*
Y169614D01*
Y169477D01*
Y169339D01*
Y169202D01*
Y169065D01*
Y168927D01*
Y168790D01*
Y168653D01*
Y168515D01*
Y168378D01*
Y168241D01*
Y168104D01*
Y167966D01*
Y167829D01*
Y167691D01*
Y167554D01*
Y167417D01*
Y167280D01*
Y167142D01*
Y167005D01*
Y166868D01*
Y166730D01*
Y166593D01*
Y166456D01*
Y166318D01*
Y166181D01*
Y166044D01*
Y165906D01*
Y165769D01*
Y165632D01*
Y165494D01*
Y165357D01*
Y165220D01*
Y165082D01*
Y164945D01*
Y164808D01*
Y164671D01*
Y164533D01*
Y164396D01*
Y164259D01*
Y164121D01*
Y163984D01*
Y163847D01*
Y163709D01*
Y163572D01*
Y163435D01*
Y163297D01*
Y163160D01*
Y163023D01*
Y162885D01*
Y162748D01*
Y162611D01*
Y162473D01*
Y162336D01*
Y162199D01*
Y162062D01*
Y161924D01*
Y161787D01*
Y161649D01*
Y161512D01*
Y161375D01*
Y161238D01*
Y161100D01*
Y160963D01*
Y160826D01*
Y160688D01*
Y160551D01*
Y160414D01*
Y160276D01*
Y160139D01*
Y160002D01*
Y159864D01*
Y159727D01*
Y159590D01*
Y159452D01*
Y159315D01*
Y159178D01*
Y159040D01*
Y158903D01*
Y158766D01*
Y158629D01*
Y158491D01*
Y158354D01*
Y158217D01*
Y158079D01*
Y157942D01*
Y157805D01*
Y157667D01*
Y157530D01*
Y157393D01*
Y157255D01*
Y157118D01*
Y156981D01*
Y156843D01*
Y156706D01*
Y156569D01*
Y156432D01*
Y156294D01*
Y156157D01*
Y156019D01*
Y155882D01*
Y155745D01*
Y155608D01*
X378742D01*
Y155470D01*
X378880D01*
Y155333D01*
X385746D01*
Y155470D01*
X385883D01*
Y155608D01*
X386020D01*
Y155745D01*
Y155882D01*
X386158D01*
Y156019D01*
Y156157D01*
Y156294D01*
Y156432D01*
Y156569D01*
Y156706D01*
Y156843D01*
Y156981D01*
Y157118D01*
Y157255D01*
Y157393D01*
Y157530D01*
Y157667D01*
Y157805D01*
Y157942D01*
Y158079D01*
Y158217D01*
Y158354D01*
Y158491D01*
Y158629D01*
Y158766D01*
Y158903D01*
Y159040D01*
Y159178D01*
Y159315D01*
Y159452D01*
Y159590D01*
Y159727D01*
Y159864D01*
Y160002D01*
Y160139D01*
Y160276D01*
Y160414D01*
Y160551D01*
Y160688D01*
Y160826D01*
Y160963D01*
Y161100D01*
Y161238D01*
Y161375D01*
Y161512D01*
Y161649D01*
Y161787D01*
Y161924D01*
Y162062D01*
Y162199D01*
Y162336D01*
Y162473D01*
Y162611D01*
Y162748D01*
Y162885D01*
Y163023D01*
Y163160D01*
Y163297D01*
Y163435D01*
Y163572D01*
Y163709D01*
Y163847D01*
Y163984D01*
Y164121D01*
Y164259D01*
Y164396D01*
Y164533D01*
Y164671D01*
Y164808D01*
Y164945D01*
Y165082D01*
Y165220D01*
Y165357D01*
Y165494D01*
Y165632D01*
Y165769D01*
Y165906D01*
Y166044D01*
Y166181D01*
Y166318D01*
Y166456D01*
Y166593D01*
Y166730D01*
Y166868D01*
Y167005D01*
Y167142D01*
Y167280D01*
Y167417D01*
Y167554D01*
Y167691D01*
Y167829D01*
Y167966D01*
Y168104D01*
Y168241D01*
Y168378D01*
Y168515D01*
Y168653D01*
Y168790D01*
Y168927D01*
Y169065D01*
Y169202D01*
Y169339D01*
Y169477D01*
Y169614D01*
Y169751D01*
Y169889D01*
Y170026D01*
Y170163D01*
Y170301D01*
Y170438D01*
Y170575D01*
Y170713D01*
Y170850D01*
Y170987D01*
Y171124D01*
Y171262D01*
Y171399D01*
Y171536D01*
Y171674D01*
Y171811D01*
Y171948D01*
Y172086D01*
Y172223D01*
Y172360D01*
Y172498D01*
Y172635D01*
Y172772D01*
Y172910D01*
Y173047D01*
Y173184D01*
Y173321D01*
Y173459D01*
Y173596D01*
Y173734D01*
Y173871D01*
Y174008D01*
Y174145D01*
Y174283D01*
Y174420D01*
Y174557D01*
Y174695D01*
Y174832D01*
Y174969D01*
Y175107D01*
Y175244D01*
Y175381D01*
Y175519D01*
Y175656D01*
Y175793D01*
Y175931D01*
Y176068D01*
Y176205D01*
Y176343D01*
Y176480D01*
Y176617D01*
Y176754D01*
Y176892D01*
Y177029D01*
Y177166D01*
Y177304D01*
Y177441D01*
Y177578D01*
Y177716D01*
Y177853D01*
Y177990D01*
Y178128D01*
Y178265D01*
Y178402D01*
Y178540D01*
Y178677D01*
Y178814D01*
Y178952D01*
Y179089D01*
Y179226D01*
Y179363D01*
Y179501D01*
Y179638D01*
Y179776D01*
Y179913D01*
Y180050D01*
Y180187D01*
Y180325D01*
Y180462D01*
Y180599D01*
Y180737D01*
Y180874D01*
Y181011D01*
Y181149D01*
Y181286D01*
Y181423D01*
Y181561D01*
Y181698D01*
Y181835D01*
Y181973D01*
Y182110D01*
Y182247D01*
Y182384D01*
Y182522D01*
Y182659D01*
Y182796D01*
Y182934D01*
Y183071D01*
Y183208D01*
Y183346D01*
Y183483D01*
Y183620D01*
Y183758D01*
Y183895D01*
Y184032D01*
Y184170D01*
Y184307D01*
Y184444D01*
Y184582D01*
X386020D01*
Y184719D01*
Y184856D01*
X385883D01*
Y184993D01*
Y185131D01*
X385471D01*
Y185268D01*
D02*
G37*
G36*
X374486D02*
X353476D01*
Y185131D01*
Y184993D01*
Y184856D01*
Y184719D01*
Y184582D01*
Y184444D01*
Y184307D01*
Y184170D01*
Y184032D01*
Y183895D01*
Y183758D01*
Y183620D01*
Y183483D01*
Y183346D01*
Y183208D01*
Y183071D01*
Y182934D01*
Y182796D01*
Y182659D01*
Y182522D01*
Y182384D01*
Y182247D01*
Y182110D01*
Y181973D01*
Y181835D01*
Y181698D01*
Y181561D01*
Y181423D01*
Y181286D01*
Y181149D01*
Y181011D01*
Y180874D01*
Y180737D01*
Y180599D01*
Y180462D01*
Y180325D01*
Y180187D01*
Y180050D01*
Y179913D01*
Y179776D01*
Y179638D01*
Y179501D01*
Y179363D01*
Y179226D01*
Y179089D01*
Y178952D01*
Y178814D01*
Y178677D01*
Y178540D01*
Y178402D01*
Y178265D01*
Y178128D01*
Y177990D01*
Y177853D01*
X353888D01*
Y177990D01*
X354025D01*
Y177853D01*
X355948D01*
Y177716D01*
Y177578D01*
Y177441D01*
Y177304D01*
Y177166D01*
Y177029D01*
Y176892D01*
Y176754D01*
Y176617D01*
Y176480D01*
Y176343D01*
Y176205D01*
Y176068D01*
Y175931D01*
Y175793D01*
Y175656D01*
Y175519D01*
Y175381D01*
Y175244D01*
Y175107D01*
Y174969D01*
Y174832D01*
Y174695D01*
Y174557D01*
Y174420D01*
Y174283D01*
Y174145D01*
Y174008D01*
Y173871D01*
Y173734D01*
Y173596D01*
Y173459D01*
Y173321D01*
Y173184D01*
Y173047D01*
Y172910D01*
Y172772D01*
Y172635D01*
Y172498D01*
Y172360D01*
Y172223D01*
Y172086D01*
Y171948D01*
Y171811D01*
Y171674D01*
Y171536D01*
Y171399D01*
Y171262D01*
Y171124D01*
Y170987D01*
Y170850D01*
Y170713D01*
Y170575D01*
Y170438D01*
Y170301D01*
Y170163D01*
Y170026D01*
Y169889D01*
Y169751D01*
Y169614D01*
Y169477D01*
Y169339D01*
Y169202D01*
Y169065D01*
Y168927D01*
Y168790D01*
Y168653D01*
Y168515D01*
Y168378D01*
Y168241D01*
Y168104D01*
Y167966D01*
Y167829D01*
Y167691D01*
Y167554D01*
Y167417D01*
Y167280D01*
Y167142D01*
Y167005D01*
Y166868D01*
Y166730D01*
Y166593D01*
Y166456D01*
Y166318D01*
Y166181D01*
Y166044D01*
Y165906D01*
Y165769D01*
Y165632D01*
Y165494D01*
Y165357D01*
Y165220D01*
Y165082D01*
Y164945D01*
Y164808D01*
Y164671D01*
Y164533D01*
Y164396D01*
Y164259D01*
Y164121D01*
Y163984D01*
Y163847D01*
Y163709D01*
Y163572D01*
Y163435D01*
Y163297D01*
Y163160D01*
Y163023D01*
Y162885D01*
Y162748D01*
Y162611D01*
Y162473D01*
Y162336D01*
Y162199D01*
Y162062D01*
Y161924D01*
Y161787D01*
Y161649D01*
Y161512D01*
Y161375D01*
Y161238D01*
Y161100D01*
Y160963D01*
Y160826D01*
Y160688D01*
Y160551D01*
Y160414D01*
Y160276D01*
Y160139D01*
Y160002D01*
Y159864D01*
Y159727D01*
Y159590D01*
Y159452D01*
Y159315D01*
Y159178D01*
Y159040D01*
Y158903D01*
Y158766D01*
Y158629D01*
Y158491D01*
Y158354D01*
Y158217D01*
Y158079D01*
Y157942D01*
Y157805D01*
Y157667D01*
Y157530D01*
Y157393D01*
Y157255D01*
Y157118D01*
Y156981D01*
Y156843D01*
Y156706D01*
Y156569D01*
Y156432D01*
Y156294D01*
Y156157D01*
Y156019D01*
Y155882D01*
Y155745D01*
X356085D01*
Y155608D01*
X356222D01*
Y155470D01*
X356360D01*
Y155333D01*
X362402D01*
Y155470D01*
X362676D01*
Y155608D01*
X362814D01*
Y155745D01*
Y155882D01*
X362951D01*
Y156019D01*
Y156157D01*
Y156294D01*
Y156432D01*
Y156569D01*
Y156706D01*
Y156843D01*
Y156981D01*
Y157118D01*
Y157255D01*
Y157393D01*
Y157530D01*
Y157667D01*
Y157805D01*
Y157942D01*
Y158079D01*
Y158217D01*
Y158354D01*
Y158491D01*
Y158629D01*
Y158766D01*
Y158903D01*
Y159040D01*
Y159178D01*
Y159315D01*
Y159452D01*
Y159590D01*
Y159727D01*
Y159864D01*
Y160002D01*
Y160139D01*
Y160276D01*
Y160414D01*
Y160551D01*
Y160688D01*
Y160826D01*
Y160963D01*
Y161100D01*
Y161238D01*
Y161375D01*
Y161512D01*
Y161649D01*
Y161787D01*
Y161924D01*
Y162062D01*
Y162199D01*
Y162336D01*
Y162473D01*
Y162611D01*
Y162748D01*
Y162885D01*
Y163023D01*
Y163160D01*
Y163297D01*
Y163435D01*
Y163572D01*
Y163709D01*
Y163847D01*
Y163984D01*
Y164121D01*
Y164259D01*
Y164396D01*
Y164533D01*
Y164671D01*
Y164808D01*
Y164945D01*
Y165082D01*
Y165220D01*
Y165357D01*
Y165494D01*
Y165632D01*
Y165769D01*
Y165906D01*
Y166044D01*
Y166181D01*
Y166318D01*
Y166456D01*
Y166593D01*
Y166730D01*
Y166868D01*
Y167005D01*
Y167142D01*
Y167280D01*
Y167417D01*
Y167554D01*
Y167691D01*
Y167829D01*
Y167966D01*
Y168104D01*
Y168241D01*
Y168378D01*
Y168515D01*
Y168653D01*
Y168790D01*
Y168927D01*
Y169065D01*
Y169202D01*
Y169339D01*
Y169477D01*
Y169614D01*
Y169751D01*
Y169889D01*
Y170026D01*
Y170163D01*
Y170301D01*
Y170438D01*
Y170575D01*
Y170713D01*
Y170850D01*
Y170987D01*
Y171124D01*
Y171262D01*
Y171399D01*
Y171536D01*
Y171674D01*
Y171811D01*
Y171948D01*
Y172086D01*
Y172223D01*
Y172360D01*
Y172498D01*
Y172635D01*
Y172772D01*
Y172910D01*
Y173047D01*
Y173184D01*
Y173321D01*
Y173459D01*
Y173596D01*
Y173734D01*
Y173871D01*
Y174008D01*
Y174145D01*
Y174283D01*
Y174420D01*
Y174557D01*
Y174695D01*
Y174832D01*
Y174969D01*
Y175107D01*
Y175244D01*
Y175381D01*
Y175519D01*
Y175656D01*
Y175793D01*
Y175931D01*
Y176068D01*
Y176205D01*
Y176343D01*
Y176480D01*
Y176617D01*
Y176754D01*
Y176892D01*
Y177029D01*
Y177166D01*
Y177304D01*
Y177441D01*
Y177578D01*
Y177716D01*
Y177853D01*
X367620D01*
Y177716D01*
Y177578D01*
Y177441D01*
Y177304D01*
Y177166D01*
Y177029D01*
Y176892D01*
Y176754D01*
Y176617D01*
Y176480D01*
Y176343D01*
Y176205D01*
Y176068D01*
Y175931D01*
Y175793D01*
Y175656D01*
Y175519D01*
Y175381D01*
Y175244D01*
Y175107D01*
Y174969D01*
Y174832D01*
Y174695D01*
Y174557D01*
Y174420D01*
Y174283D01*
Y174145D01*
Y174008D01*
Y173871D01*
Y173734D01*
Y173596D01*
Y173459D01*
Y173321D01*
Y173184D01*
Y173047D01*
Y172910D01*
Y172772D01*
Y172635D01*
Y172498D01*
Y172360D01*
Y172223D01*
Y172086D01*
Y171948D01*
Y171811D01*
Y171674D01*
Y171536D01*
Y171399D01*
Y171262D01*
Y171124D01*
Y170987D01*
Y170850D01*
Y170713D01*
Y170575D01*
Y170438D01*
Y170301D01*
Y170163D01*
Y170026D01*
Y169889D01*
Y169751D01*
Y169614D01*
Y169477D01*
Y169339D01*
Y169202D01*
Y169065D01*
Y168927D01*
Y168790D01*
Y168653D01*
Y168515D01*
Y168378D01*
Y168241D01*
Y168104D01*
Y167966D01*
Y167829D01*
Y167691D01*
Y167554D01*
Y167417D01*
Y167280D01*
Y167142D01*
Y167005D01*
Y166868D01*
Y166730D01*
Y166593D01*
Y166456D01*
Y166318D01*
Y166181D01*
Y166044D01*
Y165906D01*
Y165769D01*
Y165632D01*
Y165494D01*
Y165357D01*
Y165220D01*
Y165082D01*
Y164945D01*
Y164808D01*
Y164671D01*
Y164533D01*
Y164396D01*
Y164259D01*
Y164121D01*
Y163984D01*
Y163847D01*
Y163709D01*
Y163572D01*
Y163435D01*
Y163297D01*
Y163160D01*
Y163023D01*
Y162885D01*
Y162748D01*
Y162611D01*
Y162473D01*
Y162336D01*
Y162199D01*
Y162062D01*
Y161924D01*
Y161787D01*
Y161649D01*
Y161512D01*
Y161375D01*
Y161238D01*
Y161100D01*
Y160963D01*
Y160826D01*
Y160688D01*
Y160551D01*
Y160414D01*
Y160276D01*
Y160139D01*
Y160002D01*
Y159864D01*
Y159727D01*
Y159590D01*
Y159452D01*
Y159315D01*
Y159178D01*
Y159040D01*
Y158903D01*
Y158766D01*
Y158629D01*
Y158491D01*
Y158354D01*
Y158217D01*
Y158079D01*
Y157942D01*
Y157805D01*
Y157667D01*
Y157530D01*
Y157393D01*
Y157255D01*
Y157118D01*
Y156981D01*
Y156843D01*
Y156706D01*
Y156569D01*
Y156432D01*
Y156294D01*
Y156157D01*
Y156019D01*
Y155882D01*
X367757D01*
Y155745D01*
Y155608D01*
X367894D01*
Y155470D01*
X368032D01*
Y155333D01*
X374760D01*
Y155470D01*
X375035D01*
Y155608D01*
Y155745D01*
X375172D01*
Y155882D01*
Y156019D01*
Y156157D01*
Y156294D01*
Y156432D01*
Y156569D01*
Y156706D01*
Y156843D01*
Y156981D01*
Y157118D01*
Y157255D01*
Y157393D01*
Y157530D01*
Y157667D01*
Y157805D01*
Y157942D01*
Y158079D01*
Y158217D01*
Y158354D01*
Y158491D01*
Y158629D01*
Y158766D01*
Y158903D01*
Y159040D01*
Y159178D01*
Y159315D01*
Y159452D01*
Y159590D01*
Y159727D01*
Y159864D01*
Y160002D01*
Y160139D01*
Y160276D01*
Y160414D01*
Y160551D01*
Y160688D01*
Y160826D01*
Y160963D01*
Y161100D01*
Y161238D01*
Y161375D01*
Y161512D01*
Y161649D01*
Y161787D01*
Y161924D01*
Y162062D01*
Y162199D01*
Y162336D01*
Y162473D01*
Y162611D01*
Y162748D01*
Y162885D01*
Y163023D01*
Y163160D01*
Y163297D01*
Y163435D01*
Y163572D01*
Y163709D01*
Y163847D01*
Y163984D01*
Y164121D01*
Y164259D01*
Y164396D01*
Y164533D01*
Y164671D01*
Y164808D01*
Y164945D01*
Y165082D01*
Y165220D01*
Y165357D01*
Y165494D01*
Y165632D01*
Y165769D01*
Y165906D01*
Y166044D01*
Y166181D01*
Y166318D01*
Y166456D01*
Y166593D01*
Y166730D01*
Y166868D01*
Y167005D01*
Y167142D01*
Y167280D01*
Y167417D01*
Y167554D01*
Y167691D01*
Y167829D01*
Y167966D01*
Y168104D01*
Y168241D01*
Y168378D01*
Y168515D01*
Y168653D01*
Y168790D01*
Y168927D01*
Y169065D01*
Y169202D01*
Y169339D01*
Y169477D01*
Y169614D01*
Y169751D01*
Y169889D01*
Y170026D01*
Y170163D01*
Y170301D01*
Y170438D01*
Y170575D01*
Y170713D01*
Y170850D01*
Y170987D01*
Y171124D01*
Y171262D01*
Y171399D01*
Y171536D01*
Y171674D01*
Y171811D01*
Y171948D01*
Y172086D01*
Y172223D01*
Y172360D01*
Y172498D01*
Y172635D01*
Y172772D01*
Y172910D01*
Y173047D01*
Y173184D01*
Y173321D01*
Y173459D01*
Y173596D01*
Y173734D01*
Y173871D01*
Y174008D01*
Y174145D01*
Y174283D01*
Y174420D01*
Y174557D01*
Y174695D01*
Y174832D01*
Y174969D01*
Y175107D01*
Y175244D01*
Y175381D01*
Y175519D01*
Y175656D01*
Y175793D01*
Y175931D01*
Y176068D01*
Y176205D01*
Y176343D01*
Y176480D01*
Y176617D01*
Y176754D01*
Y176892D01*
Y177029D01*
Y177166D01*
Y177304D01*
Y177441D01*
Y177578D01*
Y177716D01*
Y177853D01*
Y177990D01*
Y178128D01*
Y178265D01*
Y178402D01*
Y178540D01*
Y178677D01*
Y178814D01*
Y178952D01*
Y179089D01*
Y179226D01*
Y179363D01*
Y179501D01*
Y179638D01*
Y179776D01*
Y179913D01*
Y180050D01*
Y180187D01*
Y180325D01*
Y180462D01*
Y180599D01*
Y180737D01*
Y180874D01*
Y181011D01*
Y181149D01*
Y181286D01*
Y181423D01*
Y181561D01*
Y181698D01*
Y181835D01*
Y181973D01*
Y182110D01*
Y182247D01*
Y182384D01*
Y182522D01*
Y182659D01*
Y182796D01*
Y182934D01*
Y183071D01*
Y183208D01*
Y183346D01*
Y183483D01*
Y183620D01*
Y183758D01*
Y183895D01*
Y184032D01*
Y184170D01*
Y184307D01*
Y184444D01*
Y184582D01*
Y184719D01*
X375035D01*
Y184856D01*
Y184993D01*
X374897D01*
Y185131D01*
X374486D01*
Y185268D01*
D02*
G37*
G36*
X380116Y152861D02*
X363638D01*
Y152724D01*
X363500D01*
Y152861D01*
X363226D01*
Y152724D01*
X362814D01*
Y152587D01*
X362676D01*
Y152449D01*
X362539D01*
Y152312D01*
Y152175D01*
Y152037D01*
Y151900D01*
Y151763D01*
Y151625D01*
Y151488D01*
Y151351D01*
Y151213D01*
Y151076D01*
Y150939D01*
Y150801D01*
Y150664D01*
Y150527D01*
Y150389D01*
Y150252D01*
Y150115D01*
Y149978D01*
Y149840D01*
Y149703D01*
Y149566D01*
Y149428D01*
Y149291D01*
Y149154D01*
Y149016D01*
Y148879D01*
Y148742D01*
Y148604D01*
Y148467D01*
Y148330D01*
Y148192D01*
Y148055D01*
Y147918D01*
Y147781D01*
Y147643D01*
Y147506D01*
Y147368D01*
Y147231D01*
Y147094D01*
Y146957D01*
Y146819D01*
Y146682D01*
Y146545D01*
Y146407D01*
Y146270D01*
Y146133D01*
Y145995D01*
Y145858D01*
X362676D01*
Y145721D01*
X362814D01*
Y145583D01*
X363226D01*
Y145446D01*
X363775D01*
Y145583D01*
X363912D01*
Y145446D01*
X377507D01*
Y145309D01*
X377644D01*
Y145171D01*
X377781D01*
Y145034D01*
Y144897D01*
Y144760D01*
Y144622D01*
Y144485D01*
Y144347D01*
Y144210D01*
Y144073D01*
Y143936D01*
Y143798D01*
Y143661D01*
Y143524D01*
Y143386D01*
Y143249D01*
Y143112D01*
Y142974D01*
Y142837D01*
Y142700D01*
Y142562D01*
Y142425D01*
Y142288D01*
Y142150D01*
Y142013D01*
Y141876D01*
Y141739D01*
Y141601D01*
Y141464D01*
Y141327D01*
Y141189D01*
Y141052D01*
Y140915D01*
Y140777D01*
Y140640D01*
Y140503D01*
Y140365D01*
Y140228D01*
Y140091D01*
Y139953D01*
Y139816D01*
Y139679D01*
Y139541D01*
Y139404D01*
Y139267D01*
Y139129D01*
Y138992D01*
Y138855D01*
Y138717D01*
Y138580D01*
Y138443D01*
Y138306D01*
Y138168D01*
Y138031D01*
Y137894D01*
Y137756D01*
Y137619D01*
Y137482D01*
Y137344D01*
Y137207D01*
Y137070D01*
Y136932D01*
Y136795D01*
Y136658D01*
Y136520D01*
Y136383D01*
Y136246D01*
Y136109D01*
Y135971D01*
Y135834D01*
Y135696D01*
Y135559D01*
Y135422D01*
Y135285D01*
Y135147D01*
Y135010D01*
Y134873D01*
Y134735D01*
Y134598D01*
Y134461D01*
Y134323D01*
Y134186D01*
Y134049D01*
Y133911D01*
Y133774D01*
Y133637D01*
Y133499D01*
Y133362D01*
Y133225D01*
Y133088D01*
Y132950D01*
Y132813D01*
Y132676D01*
Y132538D01*
Y132401D01*
Y132264D01*
Y132126D01*
Y131989D01*
Y131852D01*
Y131714D01*
Y131577D01*
Y131440D01*
Y131302D01*
Y131165D01*
Y131028D01*
Y130890D01*
Y130753D01*
Y130616D01*
X377644D01*
Y130478D01*
Y130341D01*
X377369D01*
Y130204D01*
X363088D01*
Y130066D01*
X362814D01*
Y129929D01*
X362676D01*
Y129792D01*
X362539D01*
Y129655D01*
Y129517D01*
Y129380D01*
Y129243D01*
Y129105D01*
Y128968D01*
Y128831D01*
Y128693D01*
Y128556D01*
Y128419D01*
Y128281D01*
Y128144D01*
Y128007D01*
Y127869D01*
Y127732D01*
Y127595D01*
Y127458D01*
Y127320D01*
Y127183D01*
Y127045D01*
Y126908D01*
Y126771D01*
Y126634D01*
Y126496D01*
Y126359D01*
Y126222D01*
Y126084D01*
Y125947D01*
Y125810D01*
Y125672D01*
Y125535D01*
Y125398D01*
Y125260D01*
Y125123D01*
Y124986D01*
Y124848D01*
Y124711D01*
Y124574D01*
Y124437D01*
Y124299D01*
Y124162D01*
Y124024D01*
Y123887D01*
Y123750D01*
Y123613D01*
Y123475D01*
Y123338D01*
X362676D01*
Y123201D01*
X362814D01*
Y123063D01*
X362951D01*
Y122926D01*
X380390D01*
Y123063D01*
X380802D01*
Y123201D01*
X381077D01*
Y123338D01*
X381214D01*
Y123475D01*
X381352D01*
Y123613D01*
X381489D01*
Y123750D01*
X381626D01*
Y123887D01*
X381763D01*
Y124024D01*
X381901D01*
Y124162D01*
X382038D01*
Y124299D01*
X382175D01*
Y124437D01*
X382313D01*
Y124574D01*
X382450D01*
Y124711D01*
X382587D01*
Y124848D01*
X382725D01*
Y124986D01*
X382862D01*
Y125123D01*
X382999D01*
Y125260D01*
X383137D01*
Y125398D01*
X383274D01*
Y125535D01*
X383411D01*
Y125672D01*
X383549D01*
Y125810D01*
X383686D01*
Y125947D01*
X383823D01*
Y126084D01*
X383960D01*
Y126222D01*
X384098D01*
Y126359D01*
X384235D01*
Y126496D01*
X384372D01*
Y126634D01*
X384510D01*
Y126771D01*
X384647D01*
Y126908D01*
X384784D01*
Y127045D01*
X384922D01*
Y127183D01*
X385059D01*
Y127320D01*
Y127458D01*
X385196D01*
Y127595D01*
Y127732D01*
Y127869D01*
X385334D01*
Y128007D01*
Y128144D01*
Y128281D01*
Y128419D01*
Y128556D01*
Y128693D01*
Y128831D01*
Y128968D01*
Y129105D01*
Y129243D01*
Y129380D01*
Y129517D01*
Y129655D01*
Y129792D01*
Y129929D01*
Y130066D01*
Y130204D01*
Y130341D01*
Y130478D01*
Y130616D01*
Y130753D01*
Y130890D01*
Y131028D01*
Y131165D01*
Y131302D01*
Y131440D01*
Y131577D01*
Y131714D01*
Y131852D01*
Y131989D01*
Y132126D01*
Y132264D01*
Y132401D01*
Y132538D01*
Y132676D01*
Y132813D01*
Y132950D01*
Y133088D01*
Y133225D01*
Y133362D01*
Y133499D01*
Y133637D01*
Y133774D01*
Y133911D01*
Y134049D01*
Y134186D01*
Y134323D01*
Y134461D01*
Y134598D01*
Y134735D01*
Y134873D01*
Y135010D01*
Y135147D01*
Y135285D01*
Y135422D01*
Y135559D01*
Y135696D01*
Y135834D01*
Y135971D01*
Y136109D01*
Y136246D01*
Y136383D01*
Y136520D01*
Y136658D01*
Y136795D01*
Y136932D01*
Y137070D01*
Y137207D01*
Y137344D01*
Y137482D01*
Y137619D01*
Y137756D01*
Y137894D01*
Y138031D01*
Y138168D01*
Y138306D01*
Y138443D01*
Y138580D01*
Y138717D01*
Y138855D01*
Y138992D01*
Y139129D01*
Y139267D01*
Y139404D01*
Y139541D01*
Y139679D01*
Y139816D01*
Y139953D01*
Y140091D01*
Y140228D01*
Y140365D01*
Y140503D01*
Y140640D01*
Y140777D01*
Y140915D01*
Y141052D01*
Y141189D01*
Y141327D01*
Y141464D01*
Y141601D01*
Y141739D01*
Y141876D01*
Y142013D01*
Y142150D01*
Y142288D01*
Y142425D01*
Y142562D01*
Y142700D01*
Y142837D01*
Y142974D01*
Y143112D01*
Y143249D01*
Y143386D01*
Y143524D01*
Y143661D01*
Y143798D01*
Y143936D01*
Y144073D01*
Y144210D01*
Y144347D01*
Y144485D01*
Y144622D01*
Y144760D01*
Y144897D01*
Y145034D01*
Y145171D01*
Y145309D01*
Y145446D01*
Y145583D01*
Y145721D01*
Y145858D01*
Y145995D01*
Y146133D01*
Y146270D01*
Y146407D01*
Y146545D01*
Y146682D01*
Y146819D01*
Y146957D01*
Y147094D01*
Y147231D01*
Y147368D01*
Y147506D01*
Y147643D01*
Y147781D01*
X385196D01*
Y147918D01*
Y148055D01*
Y148192D01*
Y148330D01*
X385059D01*
Y148467D01*
Y148604D01*
X384922D01*
Y148742D01*
X384784D01*
Y148879D01*
X384647D01*
Y149016D01*
X384510D01*
Y149154D01*
X384372D01*
Y149291D01*
X384235D01*
Y149428D01*
X384098D01*
Y149566D01*
X383960D01*
Y149703D01*
X383823D01*
Y149840D01*
X383686D01*
Y149978D01*
X383549D01*
Y150115D01*
X383411D01*
Y150252D01*
X383274D01*
Y150389D01*
X383137D01*
Y150527D01*
X382999D01*
Y150664D01*
X382862D01*
Y150801D01*
X382725D01*
Y150939D01*
X382587D01*
Y151076D01*
X382450D01*
Y151213D01*
X382313D01*
Y151351D01*
X382175D01*
Y151488D01*
X382038D01*
Y151625D01*
X381901D01*
Y151763D01*
X381763D01*
Y151900D01*
X381626D01*
Y152037D01*
X381489D01*
Y152175D01*
X381352D01*
Y152312D01*
X381214D01*
Y152449D01*
X380939D01*
Y152587D01*
X380528D01*
Y152724D01*
X380116D01*
Y152861D01*
D02*
G37*
G36*
X351142Y201609D02*
X348670D01*
Y201472D01*
X348121D01*
Y201334D01*
X347846D01*
Y201197D01*
X347709D01*
Y201060D01*
X347571D01*
Y200922D01*
X347434D01*
Y200785D01*
X347297D01*
Y200648D01*
X347159D01*
Y200510D01*
X347022D01*
Y200373D01*
X346885D01*
Y200236D01*
X346747D01*
Y200098D01*
X346610D01*
Y199961D01*
X346473D01*
Y199824D01*
X346335D01*
Y199687D01*
X346198D01*
Y199549D01*
X346061D01*
Y199412D01*
X345924D01*
Y199275D01*
X345786D01*
Y199137D01*
X345649D01*
Y199000D01*
X345512D01*
Y198863D01*
X345374D01*
Y198725D01*
X345237D01*
Y198588D01*
X345100D01*
Y198451D01*
X344962D01*
Y198313D01*
X344825D01*
Y198176D01*
X344688D01*
Y198039D01*
X344550D01*
Y197901D01*
X344413D01*
Y197764D01*
X344276D01*
Y197627D01*
X344138D01*
Y197489D01*
X344001D01*
Y197352D01*
Y197215D01*
X343864D01*
Y197078D01*
Y196940D01*
Y196803D01*
Y196665D01*
X343727D01*
Y196528D01*
Y196391D01*
Y196254D01*
Y196116D01*
Y195979D01*
Y195842D01*
Y195704D01*
Y195567D01*
Y195430D01*
Y195292D01*
Y195155D01*
Y195018D01*
Y194880D01*
Y194743D01*
Y194606D01*
Y194468D01*
Y194331D01*
Y194194D01*
Y194056D01*
Y193919D01*
Y193782D01*
Y193645D01*
Y193507D01*
Y193370D01*
Y193233D01*
Y193095D01*
Y192958D01*
Y192821D01*
Y192683D01*
Y192546D01*
Y192409D01*
Y192271D01*
Y192134D01*
Y191997D01*
Y191859D01*
Y191722D01*
Y191585D01*
Y191447D01*
Y191310D01*
Y191173D01*
Y191035D01*
Y190898D01*
Y190761D01*
Y190623D01*
Y190486D01*
Y190349D01*
Y190212D01*
Y190074D01*
Y189937D01*
Y189800D01*
Y189662D01*
Y189525D01*
Y189388D01*
Y189250D01*
Y189113D01*
Y188976D01*
Y188838D01*
Y188701D01*
Y188564D01*
Y188426D01*
Y188289D01*
Y188152D01*
Y188015D01*
Y187877D01*
Y187740D01*
Y187603D01*
Y187465D01*
Y187328D01*
Y187191D01*
Y187053D01*
Y186916D01*
Y186779D01*
Y186641D01*
Y186504D01*
Y186367D01*
Y186229D01*
Y186092D01*
Y185955D01*
Y185817D01*
Y185680D01*
Y185543D01*
Y185406D01*
Y185268D01*
Y185131D01*
Y184993D01*
Y184856D01*
Y184719D01*
Y184582D01*
Y184444D01*
Y184307D01*
Y184170D01*
Y184032D01*
Y183895D01*
Y183758D01*
Y183620D01*
Y183483D01*
Y183346D01*
Y183208D01*
Y183071D01*
Y182934D01*
Y182796D01*
Y182659D01*
Y182522D01*
Y182384D01*
Y182247D01*
Y182110D01*
Y181973D01*
Y181835D01*
Y181698D01*
Y181561D01*
Y181423D01*
Y181286D01*
Y181149D01*
Y181011D01*
Y180874D01*
Y180737D01*
Y180599D01*
Y180462D01*
Y180325D01*
Y180187D01*
Y180050D01*
Y179913D01*
Y179776D01*
Y179638D01*
Y179501D01*
Y179363D01*
Y179226D01*
Y179089D01*
Y178952D01*
Y178814D01*
Y178677D01*
Y178540D01*
Y178402D01*
Y178265D01*
Y178128D01*
Y177990D01*
Y177853D01*
Y177716D01*
Y177578D01*
Y177441D01*
Y177304D01*
Y177166D01*
Y177029D01*
Y176892D01*
Y176754D01*
Y176617D01*
Y176480D01*
Y176343D01*
Y176205D01*
Y176068D01*
Y175931D01*
Y175793D01*
Y175656D01*
Y175519D01*
Y175381D01*
Y175244D01*
Y175107D01*
Y174969D01*
Y174832D01*
Y174695D01*
Y174557D01*
Y174420D01*
Y174283D01*
Y174145D01*
Y174008D01*
Y173871D01*
Y173734D01*
Y173596D01*
Y173459D01*
Y173321D01*
Y173184D01*
Y173047D01*
Y172910D01*
Y172772D01*
Y172635D01*
Y172498D01*
Y172360D01*
Y172223D01*
Y172086D01*
Y171948D01*
Y171811D01*
Y171674D01*
Y171536D01*
Y171399D01*
Y171262D01*
Y171124D01*
Y170987D01*
Y170850D01*
Y170713D01*
Y170575D01*
Y170438D01*
Y170301D01*
Y170163D01*
Y170026D01*
Y169889D01*
Y169751D01*
Y169614D01*
Y169477D01*
Y169339D01*
Y169202D01*
Y169065D01*
Y168927D01*
Y168790D01*
Y168653D01*
Y168515D01*
Y168378D01*
Y168241D01*
Y168104D01*
Y167966D01*
Y167829D01*
Y167691D01*
Y167554D01*
Y167417D01*
Y167280D01*
Y167142D01*
Y167005D01*
Y166868D01*
Y166730D01*
Y166593D01*
Y166456D01*
Y166318D01*
Y166181D01*
Y166044D01*
Y165906D01*
Y165769D01*
Y165632D01*
Y165494D01*
Y165357D01*
Y165220D01*
Y165082D01*
Y164945D01*
Y164808D01*
Y164671D01*
Y164533D01*
Y164396D01*
Y164259D01*
Y164121D01*
Y163984D01*
Y163847D01*
Y163709D01*
Y163572D01*
Y163435D01*
Y163297D01*
Y163160D01*
Y163023D01*
Y162885D01*
Y162748D01*
Y162611D01*
Y162473D01*
Y162336D01*
Y162199D01*
Y162062D01*
Y161924D01*
Y161787D01*
Y161649D01*
Y161512D01*
Y161375D01*
Y161238D01*
Y161100D01*
Y160963D01*
Y160826D01*
Y160688D01*
Y160551D01*
Y160414D01*
Y160276D01*
Y160139D01*
Y160002D01*
Y159864D01*
Y159727D01*
Y159590D01*
Y159452D01*
Y159315D01*
Y159178D01*
Y159040D01*
Y158903D01*
Y158766D01*
Y158629D01*
Y158491D01*
Y158354D01*
Y158217D01*
Y158079D01*
Y157942D01*
Y157805D01*
Y157667D01*
Y157530D01*
Y157393D01*
Y157255D01*
Y157118D01*
Y156981D01*
Y156843D01*
Y156706D01*
Y156569D01*
Y156432D01*
Y156294D01*
Y156157D01*
Y156019D01*
Y155882D01*
Y155745D01*
Y155608D01*
Y155470D01*
Y155333D01*
Y155196D01*
Y155058D01*
Y154921D01*
Y154784D01*
Y154646D01*
Y154509D01*
Y154372D01*
Y154234D01*
Y154097D01*
Y153960D01*
X343864D01*
Y153822D01*
Y153685D01*
Y153548D01*
Y153411D01*
X344001D01*
Y153273D01*
Y153136D01*
X344138D01*
Y152999D01*
Y152861D01*
X344276D01*
Y152724D01*
Y152587D01*
X344413D01*
Y152449D01*
X344550D01*
Y152312D01*
Y152175D01*
X344688D01*
Y152037D01*
X344825D01*
Y151900D01*
X344962D01*
Y151763D01*
X345100D01*
Y151625D01*
X345237D01*
Y151488D01*
X345374D01*
Y151351D01*
X345512D01*
Y151213D01*
X345649D01*
Y151076D01*
X345786D01*
Y150939D01*
X345924D01*
Y150801D01*
X346061D01*
Y150664D01*
X346198D01*
Y150527D01*
X346335D01*
Y150389D01*
X346473D01*
Y150252D01*
X346610D01*
Y150115D01*
X346747D01*
Y149978D01*
X346885D01*
Y149840D01*
X347022D01*
Y149703D01*
X347159D01*
Y149566D01*
X347297D01*
Y149428D01*
X347434D01*
Y149291D01*
X347571D01*
Y149154D01*
X347709D01*
Y149016D01*
X347846D01*
Y148879D01*
X347983D01*
Y148742D01*
X348121D01*
Y148604D01*
X348258D01*
Y148467D01*
X348395D01*
Y148330D01*
X348533D01*
Y148192D01*
X348670D01*
Y148055D01*
X348945D01*
Y147918D01*
X349082D01*
Y147781D01*
X349219D01*
Y147643D01*
X349356D01*
Y147506D01*
X349494D01*
Y147368D01*
X349631D01*
Y147231D01*
X349768D01*
Y147094D01*
X349906D01*
Y146957D01*
X350043D01*
Y146819D01*
X350180D01*
Y146682D01*
X350318D01*
Y146545D01*
X350455D01*
Y146407D01*
X350592D01*
Y146270D01*
X350730D01*
Y146133D01*
X350867D01*
Y145995D01*
X351004D01*
Y145858D01*
X351142D01*
Y145721D01*
X351279D01*
Y145583D01*
X351416D01*
Y145446D01*
X351554D01*
Y145309D01*
X351691D01*
Y145171D01*
X351828D01*
Y145034D01*
X351965D01*
Y144897D01*
X352103D01*
Y144760D01*
X352240D01*
Y144622D01*
X352378D01*
Y144485D01*
X352515D01*
Y144347D01*
X352652D01*
Y144210D01*
X352789D01*
Y144073D01*
X352927D01*
Y143936D01*
X353064D01*
Y143798D01*
X353201D01*
Y143661D01*
X353339D01*
Y143524D01*
X353476D01*
Y143386D01*
X353613D01*
Y143249D01*
X353751D01*
Y143112D01*
X353888D01*
Y142974D01*
X354025D01*
Y142837D01*
X354163D01*
Y142700D01*
X354300D01*
Y142562D01*
X354437D01*
Y142425D01*
X354575D01*
Y142288D01*
X354712D01*
Y142150D01*
X354849D01*
Y142013D01*
X354986D01*
Y141876D01*
X355124D01*
Y141739D01*
X355261D01*
Y141601D01*
X355398D01*
Y141464D01*
X355536D01*
Y141327D01*
X355673D01*
Y141189D01*
X355810D01*
Y141052D01*
X355948D01*
Y140915D01*
X356085D01*
Y140777D01*
X356222D01*
Y140640D01*
X356360D01*
Y140503D01*
X356497D01*
Y140365D01*
X356634D01*
Y140228D01*
X356772D01*
Y140091D01*
X356909D01*
Y139953D01*
X357046D01*
Y139816D01*
X357184D01*
Y139679D01*
X357321D01*
Y139541D01*
X357458D01*
Y139404D01*
X357595D01*
Y139267D01*
X357733D01*
Y139129D01*
X357870D01*
Y138992D01*
X358008D01*
Y138855D01*
X358145D01*
Y138717D01*
X358282D01*
Y138580D01*
X358419D01*
Y138443D01*
X358557D01*
Y138306D01*
X358694D01*
Y138168D01*
X358831D01*
Y138031D01*
X358969D01*
Y137894D01*
X359106D01*
Y137756D01*
X359243D01*
Y137619D01*
X359381D01*
Y137482D01*
X359518D01*
Y137344D01*
X359655D01*
Y137207D01*
X359793D01*
Y137070D01*
X359930D01*
Y136932D01*
X360067D01*
Y136795D01*
X360205D01*
Y136658D01*
X360342D01*
Y136520D01*
X360616D01*
Y136383D01*
X360754D01*
Y136246D01*
X360891D01*
Y136109D01*
X361029D01*
Y135971D01*
X361166D01*
Y135834D01*
X361303D01*
Y135696D01*
X361440D01*
Y135559D01*
X361578D01*
Y135422D01*
X361715D01*
Y135285D01*
X361852D01*
Y135147D01*
X361990D01*
Y135010D01*
X362127D01*
Y134873D01*
X362264D01*
Y134735D01*
X362402D01*
Y134598D01*
X362539D01*
Y134461D01*
X362676D01*
Y134323D01*
X362814D01*
Y134186D01*
X362951D01*
Y134049D01*
X363088D01*
Y133911D01*
X363226D01*
Y133774D01*
X363363D01*
Y133637D01*
X363500D01*
Y133499D01*
X363638D01*
Y133362D01*
X363775D01*
Y133225D01*
X364049D01*
Y133362D01*
X364187D01*
Y133499D01*
X364324D01*
Y133637D01*
X364461D01*
Y133774D01*
X364599D01*
Y133911D01*
X364736D01*
Y134049D01*
X364873D01*
Y134186D01*
X365011D01*
Y134323D01*
X365148D01*
Y134461D01*
X365285D01*
Y134598D01*
Y134735D01*
X365423D01*
Y134873D01*
X365560D01*
Y135010D01*
Y135147D01*
X365697D01*
Y135285D01*
X365835D01*
Y135422D01*
Y135559D01*
Y135696D01*
Y135834D01*
Y135971D01*
Y136109D01*
Y136246D01*
Y136383D01*
Y136520D01*
Y136658D01*
Y136795D01*
Y136932D01*
Y137070D01*
Y137207D01*
Y137344D01*
Y137482D01*
Y137619D01*
Y137756D01*
Y137894D01*
Y138031D01*
Y138168D01*
Y138306D01*
Y138443D01*
Y138580D01*
Y138717D01*
Y138855D01*
Y138992D01*
Y139129D01*
Y139267D01*
Y139404D01*
Y139541D01*
Y139679D01*
Y139816D01*
Y139953D01*
Y140091D01*
Y140228D01*
Y140365D01*
Y140503D01*
Y140640D01*
Y140777D01*
Y140915D01*
Y141052D01*
Y141189D01*
Y141327D01*
Y141464D01*
X365697D01*
Y141601D01*
Y141739D01*
X365560D01*
Y141876D01*
Y142013D01*
X365423D01*
Y142150D01*
X365285D01*
Y142288D01*
Y142425D01*
X365148D01*
Y142562D01*
X365011D01*
Y142700D01*
X364873D01*
Y142837D01*
X364736D01*
Y142974D01*
X364599D01*
Y143112D01*
X364461D01*
Y143249D01*
X364324D01*
Y143386D01*
X364187D01*
Y143524D01*
X364049D01*
Y143661D01*
X363912D01*
Y143798D01*
X363775D01*
Y143936D01*
X363638D01*
Y144073D01*
X363500D01*
Y144210D01*
X363363D01*
Y144347D01*
X363226D01*
Y144485D01*
X363088D01*
Y144622D01*
X362814D01*
Y144760D01*
X362676D01*
Y144897D01*
X362539D01*
Y145034D01*
X362402D01*
Y145171D01*
X362264D01*
Y145309D01*
X362127D01*
Y145446D01*
X361990D01*
Y145583D01*
X361852D01*
Y145721D01*
X361715D01*
Y145858D01*
X361578D01*
Y145995D01*
X361440D01*
Y146133D01*
X361303D01*
Y146270D01*
X361166D01*
Y146407D01*
X361029D01*
Y146545D01*
X360891D01*
Y146682D01*
X360754D01*
Y146819D01*
X360616D01*
Y146957D01*
X360479D01*
Y147094D01*
X360342D01*
Y147231D01*
X360205D01*
Y147368D01*
X360067D01*
Y147506D01*
X359930D01*
Y147643D01*
X359793D01*
Y147781D01*
X359655D01*
Y147918D01*
X359518D01*
Y148055D01*
X359381D01*
Y148192D01*
X359243D01*
Y148330D01*
X359106D01*
Y148467D01*
X358969D01*
Y148604D01*
X358831D01*
Y148742D01*
X358694D01*
Y148879D01*
X358557D01*
Y149016D01*
X358419D01*
Y149154D01*
X358282D01*
Y149291D01*
X358145D01*
Y149428D01*
X358008D01*
Y149566D01*
X357870D01*
Y149703D01*
X357733D01*
Y149840D01*
X357595D01*
Y149978D01*
X357458D01*
Y150115D01*
X357321D01*
Y150252D01*
X357184D01*
Y150389D01*
X357046D01*
Y150527D01*
X356909D01*
Y150664D01*
X356772D01*
Y150801D01*
X356634D01*
Y150939D01*
X356497D01*
Y151076D01*
X356360D01*
Y151213D01*
X356222D01*
Y151351D01*
X356085D01*
Y151488D01*
X355948D01*
Y151625D01*
X355810D01*
Y151763D01*
X355673D01*
Y151900D01*
X355536D01*
Y152037D01*
X355398D01*
Y152175D01*
X355261D01*
Y152312D01*
X355124D01*
Y152449D01*
X354986D01*
Y152587D01*
X354849D01*
Y152724D01*
X354712D01*
Y152861D01*
X354575D01*
Y152999D01*
X354437D01*
Y153136D01*
X354300D01*
Y153273D01*
X354163D01*
Y153411D01*
X354025D01*
Y153548D01*
X353888D01*
Y153685D01*
X353751D01*
Y153822D01*
X353476D01*
Y153960D01*
X353339D01*
Y154097D01*
X353201D01*
Y154234D01*
X353064D01*
Y154372D01*
X352927D01*
Y154509D01*
X352789D01*
Y154646D01*
X352652D01*
Y154784D01*
X352515D01*
Y154921D01*
X352378D01*
Y155058D01*
X352240D01*
Y155196D01*
X352103D01*
Y155333D01*
X351965D01*
Y155470D01*
X351828D01*
Y155608D01*
X351691D01*
Y155745D01*
X351554D01*
Y155882D01*
X351416D01*
Y156019D01*
X351279D01*
Y156157D01*
X351142D01*
Y156294D01*
Y156432D01*
Y156569D01*
Y156706D01*
Y156843D01*
Y156981D01*
Y157118D01*
Y157255D01*
Y157393D01*
Y157530D01*
Y157667D01*
Y157805D01*
Y157942D01*
Y158079D01*
Y158217D01*
Y158354D01*
Y158491D01*
Y158629D01*
Y158766D01*
Y158903D01*
Y159040D01*
Y159178D01*
Y159315D01*
Y159452D01*
Y159590D01*
Y159727D01*
Y159864D01*
Y160002D01*
Y160139D01*
Y160276D01*
Y160414D01*
Y160551D01*
Y160688D01*
Y160826D01*
Y160963D01*
Y161100D01*
Y161238D01*
Y161375D01*
Y161512D01*
Y161649D01*
Y161787D01*
Y161924D01*
Y162062D01*
Y162199D01*
Y162336D01*
Y162473D01*
Y162611D01*
Y162748D01*
Y162885D01*
Y163023D01*
Y163160D01*
Y163297D01*
Y163435D01*
Y163572D01*
Y163709D01*
Y163847D01*
Y163984D01*
Y164121D01*
Y164259D01*
Y164396D01*
Y164533D01*
Y164671D01*
Y164808D01*
Y164945D01*
Y165082D01*
Y165220D01*
Y165357D01*
Y165494D01*
Y165632D01*
Y165769D01*
Y165906D01*
Y166044D01*
Y166181D01*
Y166318D01*
Y166456D01*
Y166593D01*
Y166730D01*
Y166868D01*
Y167005D01*
Y167142D01*
Y167280D01*
Y167417D01*
Y167554D01*
Y167691D01*
Y167829D01*
Y167966D01*
Y168104D01*
Y168241D01*
Y168378D01*
Y168515D01*
Y168653D01*
Y168790D01*
Y168927D01*
Y169065D01*
Y169202D01*
Y169339D01*
Y169477D01*
Y169614D01*
Y169751D01*
Y169889D01*
Y170026D01*
Y170163D01*
Y170301D01*
Y170438D01*
Y170575D01*
Y170713D01*
Y170850D01*
Y170987D01*
Y171124D01*
Y171262D01*
Y171399D01*
Y171536D01*
Y171674D01*
Y171811D01*
Y171948D01*
Y172086D01*
Y172223D01*
Y172360D01*
Y172498D01*
Y172635D01*
Y172772D01*
Y172910D01*
Y173047D01*
Y173184D01*
Y173321D01*
Y173459D01*
Y173596D01*
Y173734D01*
Y173871D01*
Y174008D01*
Y174145D01*
Y174283D01*
Y174420D01*
Y174557D01*
Y174695D01*
Y174832D01*
Y174969D01*
Y175107D01*
Y175244D01*
Y175381D01*
Y175519D01*
Y175656D01*
Y175793D01*
Y175931D01*
Y176068D01*
Y176205D01*
Y176343D01*
Y176480D01*
Y176617D01*
Y176754D01*
Y176892D01*
Y177029D01*
Y177166D01*
Y177304D01*
Y177441D01*
Y177578D01*
Y177716D01*
Y177853D01*
Y177990D01*
Y178128D01*
Y178265D01*
Y178402D01*
Y178540D01*
Y178677D01*
Y178814D01*
Y178952D01*
Y179089D01*
Y179226D01*
Y179363D01*
Y179501D01*
Y179638D01*
Y179776D01*
Y179913D01*
Y180050D01*
Y180187D01*
Y180325D01*
Y180462D01*
Y180599D01*
Y180737D01*
Y180874D01*
Y181011D01*
Y181149D01*
Y181286D01*
Y181423D01*
Y181561D01*
Y181698D01*
Y181835D01*
Y181973D01*
Y182110D01*
Y182247D01*
Y182384D01*
Y182522D01*
Y182659D01*
Y182796D01*
Y182934D01*
Y183071D01*
Y183208D01*
Y183346D01*
Y183483D01*
Y183620D01*
Y183758D01*
Y183895D01*
Y184032D01*
Y184170D01*
Y184307D01*
Y184444D01*
Y184582D01*
Y184719D01*
Y184856D01*
Y184993D01*
Y185131D01*
Y185268D01*
Y185406D01*
Y185543D01*
Y185680D01*
Y185817D01*
Y185955D01*
Y186092D01*
Y186229D01*
Y186367D01*
Y186504D01*
Y186641D01*
Y186779D01*
Y186916D01*
Y187053D01*
Y187191D01*
Y187328D01*
Y187465D01*
Y187603D01*
Y187740D01*
Y187877D01*
Y188015D01*
Y188152D01*
Y188289D01*
Y188426D01*
Y188564D01*
Y188701D01*
Y188838D01*
Y188976D01*
Y189113D01*
Y189250D01*
Y189388D01*
Y189525D01*
Y189662D01*
Y189800D01*
Y189937D01*
Y190074D01*
Y190212D01*
Y190349D01*
Y190486D01*
Y190623D01*
Y190761D01*
Y190898D01*
Y191035D01*
Y191173D01*
Y191310D01*
Y191447D01*
Y191585D01*
Y191722D01*
Y191859D01*
Y191997D01*
Y192134D01*
Y192271D01*
Y192409D01*
Y192546D01*
Y192683D01*
Y192821D01*
Y192958D01*
Y193095D01*
Y193233D01*
Y193370D01*
Y193507D01*
Y193645D01*
Y193782D01*
Y193919D01*
Y194056D01*
Y194194D01*
Y194331D01*
Y194468D01*
Y194606D01*
Y194743D01*
Y194880D01*
Y195018D01*
Y195155D01*
Y195292D01*
Y195430D01*
Y195567D01*
Y195704D01*
Y195842D01*
Y195979D01*
Y196116D01*
Y196254D01*
Y196391D01*
Y196528D01*
Y196665D01*
Y196803D01*
Y196940D01*
Y197078D01*
Y197215D01*
Y197352D01*
Y197489D01*
Y197627D01*
Y197764D01*
Y197901D01*
Y198039D01*
Y198176D01*
Y198313D01*
Y198451D01*
Y198588D01*
Y198725D01*
Y198863D01*
Y199000D01*
Y199137D01*
Y199275D01*
Y199412D01*
Y199549D01*
Y199687D01*
Y199824D01*
Y199961D01*
Y200098D01*
Y200236D01*
Y200373D01*
Y200510D01*
Y200648D01*
Y200785D01*
Y200922D01*
Y201060D01*
Y201197D01*
Y201334D01*
Y201472D01*
Y201609D01*
D02*
G37*
G36*
X341117Y152861D02*
X339195D01*
Y152724D01*
X338646D01*
Y152587D01*
X338371D01*
Y152449D01*
X338097D01*
Y152312D01*
X337959D01*
Y152175D01*
X337822D01*
Y152037D01*
X337685D01*
Y151900D01*
X337547D01*
Y151763D01*
X337410D01*
Y151625D01*
X337272D01*
Y151488D01*
X337135D01*
Y151351D01*
X336998D01*
Y151213D01*
X336861D01*
Y151076D01*
X336723D01*
Y150939D01*
X336586D01*
Y150801D01*
X336449D01*
Y150664D01*
X336311D01*
Y150527D01*
X336174D01*
Y150389D01*
X336037D01*
Y150252D01*
X335899D01*
Y150115D01*
X335762D01*
Y149978D01*
X335625D01*
Y149840D01*
X335487D01*
Y149703D01*
X335350D01*
Y149566D01*
X335213D01*
Y149428D01*
X335075D01*
Y149291D01*
X334938D01*
Y149154D01*
X334801D01*
Y149016D01*
X334664D01*
Y148879D01*
X334526D01*
Y148742D01*
X334389D01*
Y148604D01*
X334252D01*
Y148467D01*
Y148330D01*
Y148192D01*
X334114D01*
Y148055D01*
Y147918D01*
Y147781D01*
Y147643D01*
X333977D01*
Y147506D01*
Y147368D01*
Y147231D01*
Y147094D01*
Y146957D01*
Y146819D01*
Y146682D01*
Y146545D01*
Y146407D01*
Y146270D01*
Y146133D01*
Y145995D01*
Y145858D01*
Y145721D01*
Y145583D01*
Y145446D01*
Y145309D01*
Y145171D01*
Y145034D01*
Y144897D01*
Y144760D01*
Y144622D01*
Y144485D01*
Y144347D01*
Y144210D01*
Y144073D01*
Y143936D01*
Y143798D01*
Y143661D01*
Y143524D01*
Y143386D01*
Y143249D01*
Y143112D01*
Y142974D01*
Y142837D01*
Y142700D01*
Y142562D01*
Y142425D01*
Y142288D01*
Y142150D01*
Y142013D01*
Y141876D01*
Y141739D01*
Y141601D01*
Y141464D01*
Y141327D01*
Y141189D01*
Y141052D01*
Y140915D01*
Y140777D01*
Y140640D01*
Y140503D01*
Y140365D01*
Y140228D01*
Y140091D01*
Y139953D01*
Y139816D01*
Y139679D01*
Y139541D01*
Y139404D01*
Y139267D01*
Y139129D01*
Y138992D01*
Y138855D01*
Y138717D01*
Y138580D01*
Y138443D01*
Y138306D01*
Y138168D01*
Y138031D01*
Y137894D01*
Y137756D01*
Y137619D01*
Y137482D01*
Y137344D01*
Y137207D01*
Y137070D01*
Y136932D01*
Y136795D01*
Y136658D01*
Y136520D01*
Y136383D01*
Y136246D01*
Y136109D01*
Y135971D01*
Y135834D01*
Y135696D01*
Y135559D01*
Y135422D01*
Y135285D01*
Y135147D01*
Y135010D01*
Y134873D01*
Y134735D01*
Y134598D01*
Y134461D01*
Y134323D01*
Y134186D01*
Y134049D01*
Y133911D01*
Y133774D01*
Y133637D01*
Y133499D01*
Y133362D01*
Y133225D01*
Y133088D01*
Y132950D01*
Y132813D01*
Y132676D01*
Y132538D01*
Y132401D01*
Y132264D01*
Y132126D01*
Y131989D01*
Y131852D01*
Y131714D01*
Y131577D01*
Y131440D01*
Y131302D01*
Y131165D01*
Y131028D01*
Y130890D01*
Y130753D01*
Y130616D01*
Y130478D01*
Y130341D01*
Y130204D01*
Y130066D01*
Y129929D01*
Y129792D01*
Y129655D01*
Y129517D01*
Y129380D01*
Y129243D01*
Y129105D01*
Y128968D01*
Y128831D01*
Y128693D01*
Y128556D01*
Y128419D01*
Y128281D01*
Y128144D01*
Y128007D01*
Y127869D01*
Y127732D01*
Y127595D01*
Y127458D01*
Y127320D01*
Y127183D01*
Y127045D01*
Y126908D01*
Y126771D01*
Y126634D01*
Y126496D01*
Y126359D01*
Y126222D01*
Y126084D01*
Y125947D01*
Y125810D01*
Y125672D01*
Y125535D01*
Y125398D01*
Y125260D01*
Y125123D01*
Y124986D01*
Y124848D01*
Y124711D01*
Y124574D01*
Y124437D01*
Y124299D01*
Y124162D01*
Y124024D01*
Y123887D01*
Y123750D01*
Y123613D01*
Y123475D01*
X334114D01*
Y123338D01*
Y123201D01*
X334252D01*
Y123063D01*
X334526D01*
Y122926D01*
X340980D01*
Y123063D01*
X341255D01*
Y123201D01*
X341392D01*
Y123338D01*
X341529D01*
Y123475D01*
Y123613D01*
Y123750D01*
Y123887D01*
Y124024D01*
Y124162D01*
Y124299D01*
Y124437D01*
Y124574D01*
Y124711D01*
Y124848D01*
Y124986D01*
Y125123D01*
Y125260D01*
Y125398D01*
Y125535D01*
Y125672D01*
Y125810D01*
Y125947D01*
Y126084D01*
Y126222D01*
Y126359D01*
Y126496D01*
Y126634D01*
Y126771D01*
Y126908D01*
Y127045D01*
Y127183D01*
Y127320D01*
Y127458D01*
Y127595D01*
Y127732D01*
Y127869D01*
Y128007D01*
Y128144D01*
Y128281D01*
Y128419D01*
Y128556D01*
Y128693D01*
Y128831D01*
Y128968D01*
Y129105D01*
Y129243D01*
Y129380D01*
Y129517D01*
Y129655D01*
Y129792D01*
Y129929D01*
Y130066D01*
Y130204D01*
Y130341D01*
Y130478D01*
Y130616D01*
Y130753D01*
Y130890D01*
Y131028D01*
Y131165D01*
Y131302D01*
Y131440D01*
Y131577D01*
Y131714D01*
X341667D01*
Y131852D01*
Y131989D01*
X341941D01*
Y132126D01*
X351142D01*
Y131989D01*
X351416D01*
Y131852D01*
Y131714D01*
X351554D01*
Y131577D01*
Y131440D01*
Y131302D01*
Y131165D01*
Y131028D01*
Y130890D01*
Y130753D01*
Y130616D01*
Y130478D01*
Y130341D01*
Y130204D01*
Y130066D01*
Y129929D01*
Y129792D01*
Y129655D01*
Y129517D01*
Y129380D01*
Y129243D01*
Y129105D01*
Y128968D01*
Y128831D01*
Y128693D01*
Y128556D01*
Y128419D01*
Y128281D01*
Y128144D01*
Y128007D01*
Y127869D01*
Y127732D01*
Y127595D01*
Y127458D01*
Y127320D01*
Y127183D01*
Y127045D01*
Y126908D01*
Y126771D01*
Y126634D01*
Y126496D01*
Y126359D01*
Y126222D01*
Y126084D01*
Y125947D01*
Y125810D01*
Y125672D01*
Y125535D01*
Y125398D01*
Y125260D01*
Y125123D01*
Y124986D01*
Y124848D01*
Y124711D01*
Y124574D01*
Y124437D01*
Y124299D01*
Y124162D01*
Y124024D01*
Y123887D01*
Y123750D01*
Y123613D01*
Y123475D01*
X351691D01*
Y123338D01*
Y123201D01*
X351828D01*
Y123063D01*
X352103D01*
Y122926D01*
X358557D01*
Y123063D01*
X358831D01*
Y123201D01*
X358969D01*
Y123338D01*
X359106D01*
Y123475D01*
Y123613D01*
Y123750D01*
Y123887D01*
Y124024D01*
Y124162D01*
Y124299D01*
Y124437D01*
Y124574D01*
Y124711D01*
Y124848D01*
Y124986D01*
Y125123D01*
Y125260D01*
Y125398D01*
Y125535D01*
Y125672D01*
Y125810D01*
Y125947D01*
Y126084D01*
Y126222D01*
Y126359D01*
Y126496D01*
Y126634D01*
Y126771D01*
Y126908D01*
Y127045D01*
Y127183D01*
Y127320D01*
Y127458D01*
Y127595D01*
Y127732D01*
Y127869D01*
Y128007D01*
Y128144D01*
Y128281D01*
Y128419D01*
Y128556D01*
Y128693D01*
Y128831D01*
Y128968D01*
Y129105D01*
Y129243D01*
Y129380D01*
Y129517D01*
Y129655D01*
Y129792D01*
Y129929D01*
Y130066D01*
Y130204D01*
Y130341D01*
Y130478D01*
Y130616D01*
Y130753D01*
Y130890D01*
Y131028D01*
Y131165D01*
Y131302D01*
Y131440D01*
Y131577D01*
Y131714D01*
Y131852D01*
Y131989D01*
Y132126D01*
Y132264D01*
Y132401D01*
Y132538D01*
Y132676D01*
Y132813D01*
Y132950D01*
Y133088D01*
Y133225D01*
Y133362D01*
Y133499D01*
Y133637D01*
Y133774D01*
Y133911D01*
Y134049D01*
Y134186D01*
Y134323D01*
X358969D01*
Y134461D01*
X358831D01*
Y134598D01*
X358694D01*
Y134735D01*
X358557D01*
Y134873D01*
X358419D01*
Y135010D01*
X358282D01*
Y135147D01*
X358008D01*
Y135285D01*
X357870D01*
Y135422D01*
X357733D01*
Y135559D01*
X357595D01*
Y135696D01*
X357458D01*
Y135834D01*
X357321D01*
Y135971D01*
X357184D01*
Y136109D01*
X357046D01*
Y136246D01*
X356909D01*
Y136383D01*
X356772D01*
Y136520D01*
X356634D01*
Y136658D01*
X356497D01*
Y136795D01*
X356360D01*
Y136932D01*
X356222D01*
Y137070D01*
X356085D01*
Y137207D01*
X355948D01*
Y137344D01*
X355810D01*
Y137482D01*
X355673D01*
Y137619D01*
X355536D01*
Y137756D01*
X355398D01*
Y137894D01*
X355261D01*
Y138031D01*
X355124D01*
Y138168D01*
X354986D01*
Y138306D01*
X354849D01*
Y138443D01*
X354712D01*
Y138580D01*
X354575D01*
Y138717D01*
X354437D01*
Y138855D01*
X354300D01*
Y138992D01*
X354163D01*
Y139129D01*
X354025D01*
Y139267D01*
X353888D01*
Y139404D01*
X353751D01*
Y139541D01*
X353613D01*
Y139679D01*
X353476D01*
Y139816D01*
X353339D01*
Y139953D01*
X353201D01*
Y140091D01*
X353064D01*
Y140228D01*
X352927D01*
Y140365D01*
X352789D01*
Y140503D01*
X352652D01*
Y140640D01*
X352515D01*
Y140777D01*
X352378D01*
Y140915D01*
X352240D01*
Y141052D01*
X352103D01*
Y141189D01*
X351965D01*
Y141327D01*
X351828D01*
Y141464D01*
X351691D01*
Y141601D01*
X351554D01*
Y141464D01*
Y141327D01*
Y141189D01*
Y141052D01*
Y140915D01*
Y140777D01*
Y140640D01*
Y140503D01*
Y140365D01*
Y140228D01*
Y140091D01*
Y139953D01*
Y139816D01*
Y139679D01*
Y139541D01*
Y139404D01*
Y139267D01*
Y139129D01*
Y138992D01*
Y138855D01*
Y138717D01*
Y138580D01*
X341529D01*
Y138717D01*
Y138855D01*
Y138992D01*
Y139129D01*
Y139267D01*
Y139404D01*
Y139541D01*
Y139679D01*
Y139816D01*
Y139953D01*
Y140091D01*
Y140228D01*
Y140365D01*
Y140503D01*
Y140640D01*
Y140777D01*
Y140915D01*
Y141052D01*
Y141189D01*
Y141327D01*
Y141464D01*
Y141601D01*
Y141739D01*
Y141876D01*
Y142013D01*
Y142150D01*
Y142288D01*
Y142425D01*
Y142562D01*
Y142700D01*
Y142837D01*
Y142974D01*
Y143112D01*
Y143249D01*
Y143386D01*
Y143524D01*
Y143661D01*
Y143798D01*
Y143936D01*
Y144073D01*
Y144210D01*
Y144347D01*
Y144485D01*
Y144622D01*
Y144760D01*
Y144897D01*
Y145034D01*
Y145171D01*
Y145309D01*
Y145446D01*
Y145583D01*
Y145721D01*
Y145858D01*
Y145995D01*
Y146133D01*
X347709D01*
Y146270D01*
X347571D01*
Y146407D01*
X347434D01*
Y146545D01*
X347297D01*
Y146682D01*
X347159D01*
Y146819D01*
X347022D01*
Y146957D01*
X346885D01*
Y147094D01*
X346747D01*
Y147231D01*
X346610D01*
Y147368D01*
X346473D01*
Y147506D01*
X346335D01*
Y147643D01*
X346198D01*
Y147781D01*
X346061D01*
Y147918D01*
X345924D01*
Y148055D01*
X345786D01*
Y148192D01*
X345649D01*
Y148330D01*
X345512D01*
Y148467D01*
X345374D01*
Y148604D01*
X345237D01*
Y148742D01*
X345100D01*
Y148879D01*
X344962D01*
Y149016D01*
X344825D01*
Y149154D01*
X344688D01*
Y149291D01*
X344550D01*
Y149428D01*
X344413D01*
Y149566D01*
X344276D01*
Y149703D01*
X344138D01*
Y149840D01*
X344001D01*
Y149978D01*
X343864D01*
Y150115D01*
X343727D01*
Y150252D01*
X343589D01*
Y150389D01*
X343452D01*
Y150527D01*
X343315D01*
Y150664D01*
X343177D01*
Y150801D01*
X343040D01*
Y150939D01*
X342903D01*
Y151076D01*
X342765D01*
Y151213D01*
X342628D01*
Y151351D01*
X342491D01*
Y151488D01*
X342353D01*
Y151625D01*
X342216D01*
Y151763D01*
X342079D01*
Y151900D01*
X341941D01*
Y152037D01*
X341804D01*
Y152175D01*
X341667D01*
Y152312D01*
X341529D01*
Y152449D01*
X341392D01*
Y152587D01*
X341255D01*
Y152724D01*
X341117D01*
Y152861D01*
D02*
G37*
G36*
X330407D02*
X311457D01*
Y152724D01*
X310770D01*
Y152587D01*
X310358D01*
Y152449D01*
X310084D01*
Y152312D01*
X309946D01*
Y152175D01*
X309809D01*
Y152037D01*
X309672D01*
Y151900D01*
X309534D01*
Y151763D01*
X309397D01*
Y151625D01*
X309260D01*
Y151488D01*
X309122D01*
Y151351D01*
X308985D01*
Y151213D01*
X308848D01*
Y151076D01*
X308710D01*
Y150939D01*
X308573D01*
Y150801D01*
X308436D01*
Y150664D01*
X308298D01*
Y150527D01*
X308161D01*
Y150389D01*
X308024D01*
Y150252D01*
X307887D01*
Y150115D01*
X307749D01*
Y149978D01*
X307612D01*
Y149840D01*
X307475D01*
Y149703D01*
X307337D01*
Y149566D01*
X307200D01*
Y149428D01*
X307063D01*
Y149291D01*
X306925D01*
Y149154D01*
X306788D01*
Y149016D01*
X306651D01*
Y148879D01*
X306513D01*
Y148742D01*
X306376D01*
Y148604D01*
X306239D01*
Y148467D01*
Y148330D01*
X306101D01*
Y148192D01*
Y148055D01*
Y147918D01*
X305964D01*
Y147781D01*
Y147643D01*
Y147506D01*
Y147368D01*
Y147231D01*
Y147094D01*
Y146957D01*
Y146819D01*
Y146682D01*
Y146545D01*
Y146407D01*
Y146270D01*
Y146133D01*
Y145995D01*
Y145858D01*
Y145721D01*
Y145583D01*
Y145446D01*
Y145309D01*
Y145171D01*
Y145034D01*
Y144897D01*
Y144760D01*
Y144622D01*
Y144485D01*
Y144347D01*
Y144210D01*
Y144073D01*
Y143936D01*
Y143798D01*
Y143661D01*
Y143524D01*
Y143386D01*
Y143249D01*
Y143112D01*
Y142974D01*
Y142837D01*
Y142700D01*
Y142562D01*
Y142425D01*
Y142288D01*
Y142150D01*
Y142013D01*
Y141876D01*
Y141739D01*
Y141601D01*
Y141464D01*
Y141327D01*
Y141189D01*
Y141052D01*
Y140915D01*
Y140777D01*
Y140640D01*
Y140503D01*
Y140365D01*
Y140228D01*
Y140091D01*
Y139953D01*
Y139816D01*
Y139679D01*
Y139541D01*
Y139404D01*
Y139267D01*
Y139129D01*
Y138992D01*
Y138855D01*
Y138717D01*
Y138580D01*
Y138443D01*
Y138306D01*
Y138168D01*
Y138031D01*
Y137894D01*
Y137756D01*
Y137619D01*
Y137482D01*
Y137344D01*
Y137207D01*
Y137070D01*
X306101D01*
Y136932D01*
Y136795D01*
X306239D01*
Y136658D01*
Y136520D01*
X306376D01*
Y136383D01*
X306513D01*
Y136246D01*
X306651D01*
Y136109D01*
X306788D01*
Y135971D01*
X306925D01*
Y135834D01*
X307063D01*
Y135696D01*
Y135559D01*
X307200D01*
Y135422D01*
X307337D01*
Y135285D01*
X307475D01*
Y135147D01*
X307612D01*
Y135010D01*
X307749D01*
Y134873D01*
X307887D01*
Y134735D01*
X308024D01*
Y134598D01*
X308161D01*
Y134461D01*
X308298D01*
Y134323D01*
X308436D01*
Y134186D01*
X308573D01*
Y134049D01*
X308710D01*
Y133911D01*
X308848D01*
Y133774D01*
X308985D01*
Y133637D01*
X309122D01*
Y133499D01*
X309260D01*
Y133362D01*
X309397D01*
Y133225D01*
X309534D01*
Y133088D01*
X309672D01*
Y132950D01*
X309809D01*
Y132813D01*
X309946D01*
Y132676D01*
X310084D01*
Y132538D01*
X310221D01*
Y132401D01*
Y132264D01*
X310084D01*
Y132126D01*
X309946D01*
Y131989D01*
Y131852D01*
X309809D01*
Y131714D01*
Y131577D01*
X309672D01*
Y131440D01*
X309534D01*
Y131302D01*
Y131165D01*
X309397D01*
Y131028D01*
Y130890D01*
X309260D01*
Y130753D01*
Y130616D01*
X309122D01*
Y130478D01*
X308985D01*
Y130341D01*
Y130204D01*
X308848D01*
Y130066D01*
Y129929D01*
X308710D01*
Y129792D01*
X308573D01*
Y129655D01*
Y129517D01*
X308436D01*
Y129380D01*
Y129243D01*
X308298D01*
Y129105D01*
X308161D01*
Y128968D01*
Y128831D01*
X308024D01*
Y128693D01*
Y128556D01*
X307887D01*
Y128419D01*
X307749D01*
Y128281D01*
Y128144D01*
X307612D01*
Y128007D01*
Y127869D01*
X307475D01*
Y127732D01*
X307337D01*
Y127595D01*
Y127458D01*
X307200D01*
Y127320D01*
Y127183D01*
X307063D01*
Y127045D01*
X306925D01*
Y126908D01*
Y126771D01*
X306788D01*
Y126634D01*
Y126496D01*
X306651D01*
Y126359D01*
X306513D01*
Y126222D01*
Y126084D01*
X306376D01*
Y125947D01*
Y125810D01*
X306239D01*
Y125672D01*
X306101D01*
Y125535D01*
Y125398D01*
X305964D01*
Y125260D01*
Y125123D01*
X305827D01*
Y124986D01*
X305690D01*
Y124848D01*
Y124711D01*
X305552D01*
Y124574D01*
Y124437D01*
X305415D01*
Y124299D01*
X305278D01*
Y124162D01*
Y124024D01*
X305140D01*
Y123887D01*
Y123750D01*
X305003D01*
Y123613D01*
X304866D01*
Y123475D01*
Y123338D01*
Y123201D01*
Y123063D01*
X305003D01*
Y122926D01*
X312693D01*
Y123063D01*
X312967D01*
Y123201D01*
X313105D01*
Y123338D01*
X313242D01*
Y123475D01*
X313379D01*
Y123613D01*
X313517D01*
Y123750D01*
Y123887D01*
X313654D01*
Y124024D01*
Y124162D01*
X313791D01*
Y124299D01*
X313929D01*
Y124437D01*
Y124574D01*
X314066D01*
Y124711D01*
Y124848D01*
X314203D01*
Y124986D01*
Y125123D01*
X314340D01*
Y125260D01*
X314478D01*
Y125398D01*
Y125535D01*
X314615D01*
Y125672D01*
Y125810D01*
X314753D01*
Y125947D01*
X314890D01*
Y126084D01*
Y126222D01*
X315027D01*
Y126359D01*
Y126496D01*
X315164D01*
Y126634D01*
X315302D01*
Y126771D01*
Y126908D01*
X315439D01*
Y127045D01*
Y127183D01*
X315576D01*
Y127320D01*
X315714D01*
Y127458D01*
Y127595D01*
X315851D01*
Y127732D01*
Y127869D01*
X315988D01*
Y128007D01*
Y128144D01*
X316126D01*
Y128281D01*
X316263D01*
Y128419D01*
Y128556D01*
X316400D01*
Y128693D01*
Y128831D01*
X316538D01*
Y128968D01*
X316675D01*
Y129105D01*
Y129243D01*
X316812D01*
Y129380D01*
Y129517D01*
X316950D01*
Y129655D01*
X317087D01*
Y129792D01*
Y129929D01*
X317224D01*
Y130066D01*
Y130204D01*
X317362D01*
Y130341D01*
Y130478D01*
X317499D01*
Y130616D01*
X317636D01*
Y130753D01*
Y130890D01*
X317773D01*
Y131028D01*
Y131165D01*
X317911D01*
Y131302D01*
X318048D01*
Y131440D01*
Y131577D01*
X318185D01*
Y131714D01*
Y131852D01*
X323404D01*
Y131714D01*
Y131577D01*
Y131440D01*
Y131302D01*
Y131165D01*
X323541D01*
Y131028D01*
X323404D01*
Y130890D01*
Y130753D01*
Y130616D01*
Y130478D01*
Y130341D01*
Y130204D01*
Y130066D01*
Y129929D01*
Y129792D01*
Y129655D01*
Y129517D01*
Y129380D01*
Y129243D01*
Y129105D01*
Y128968D01*
Y128831D01*
Y128693D01*
Y128556D01*
Y128419D01*
Y128281D01*
Y128144D01*
Y128007D01*
Y127869D01*
Y127732D01*
Y127595D01*
Y127458D01*
Y127320D01*
Y127183D01*
Y127045D01*
Y126908D01*
Y126771D01*
Y126634D01*
Y126496D01*
Y126359D01*
Y126222D01*
Y126084D01*
Y125947D01*
Y125810D01*
Y125672D01*
Y125535D01*
Y125398D01*
Y125260D01*
Y125123D01*
Y124986D01*
Y124848D01*
Y124711D01*
Y124574D01*
Y124437D01*
Y124299D01*
Y124162D01*
Y124024D01*
Y123887D01*
Y123750D01*
Y123613D01*
X323541D01*
Y123475D01*
Y123338D01*
Y123201D01*
X323678D01*
Y123063D01*
X323815D01*
Y122926D01*
X330544D01*
Y123063D01*
X330819D01*
Y123201D01*
X330956D01*
Y123338D01*
Y123475D01*
Y123613D01*
X331093D01*
Y123750D01*
X330956D01*
Y123887D01*
X331093D01*
Y124024D01*
Y124162D01*
Y124299D01*
Y124437D01*
Y124574D01*
Y124711D01*
Y124848D01*
Y124986D01*
Y125123D01*
Y125260D01*
Y125398D01*
Y125535D01*
Y125672D01*
Y125810D01*
Y125947D01*
Y126084D01*
Y126222D01*
Y126359D01*
Y126496D01*
Y126634D01*
Y126771D01*
Y126908D01*
Y127045D01*
Y127183D01*
Y127320D01*
Y127458D01*
Y127595D01*
Y127732D01*
Y127869D01*
Y128007D01*
Y128144D01*
Y128281D01*
Y128419D01*
Y128556D01*
Y128693D01*
Y128831D01*
Y128968D01*
Y129105D01*
Y129243D01*
Y129380D01*
Y129517D01*
Y129655D01*
Y129792D01*
Y129929D01*
Y130066D01*
Y130204D01*
Y130341D01*
Y130478D01*
Y130616D01*
Y130753D01*
Y130890D01*
Y131028D01*
Y131165D01*
Y131302D01*
Y131440D01*
Y131577D01*
Y131714D01*
Y131852D01*
Y131989D01*
Y132126D01*
Y132264D01*
Y132401D01*
Y132538D01*
Y132676D01*
Y132813D01*
Y132950D01*
Y133088D01*
Y133225D01*
Y133362D01*
Y133499D01*
Y133637D01*
Y133774D01*
Y133911D01*
Y134049D01*
Y134186D01*
Y134323D01*
Y134461D01*
Y134598D01*
Y134735D01*
Y134873D01*
Y135010D01*
Y135147D01*
Y135285D01*
Y135422D01*
Y135559D01*
Y135696D01*
Y135834D01*
Y135971D01*
Y136109D01*
Y136246D01*
Y136383D01*
Y136520D01*
Y136658D01*
Y136795D01*
Y136932D01*
Y137070D01*
Y137207D01*
Y137344D01*
Y137482D01*
Y137619D01*
Y137756D01*
Y137894D01*
Y138031D01*
Y138168D01*
Y138306D01*
Y138443D01*
Y138580D01*
Y138717D01*
Y138855D01*
Y138992D01*
Y139129D01*
Y139267D01*
Y139404D01*
Y139541D01*
Y139679D01*
Y139816D01*
Y139953D01*
Y140091D01*
Y140228D01*
Y140365D01*
Y140503D01*
Y140640D01*
Y140777D01*
Y140915D01*
Y141052D01*
Y141189D01*
Y141327D01*
Y141464D01*
Y141601D01*
Y141739D01*
Y141876D01*
Y142013D01*
Y142150D01*
Y142288D01*
Y142425D01*
Y142562D01*
Y142700D01*
Y142837D01*
Y142974D01*
Y143112D01*
Y143249D01*
Y143386D01*
Y143524D01*
Y143661D01*
Y143798D01*
Y143936D01*
Y144073D01*
Y144210D01*
Y144347D01*
Y144485D01*
Y144622D01*
Y144760D01*
Y144897D01*
Y145034D01*
Y145171D01*
Y145309D01*
Y145446D01*
Y145583D01*
Y145721D01*
Y145858D01*
Y145995D01*
Y146133D01*
Y146270D01*
Y146407D01*
Y146545D01*
Y146682D01*
Y146819D01*
Y146957D01*
Y147094D01*
Y147231D01*
Y147368D01*
Y147506D01*
Y147643D01*
Y147781D01*
Y147918D01*
Y148055D01*
Y148192D01*
Y148330D01*
Y148467D01*
Y148604D01*
Y148742D01*
Y148879D01*
Y149016D01*
Y149154D01*
Y149291D01*
Y149428D01*
Y149566D01*
Y149703D01*
Y149840D01*
Y149978D01*
Y150115D01*
Y150252D01*
Y150389D01*
Y150527D01*
Y150664D01*
Y150801D01*
Y150939D01*
Y151076D01*
Y151213D01*
Y151351D01*
Y151488D01*
Y151625D01*
Y151763D01*
Y151900D01*
Y152037D01*
X330956D01*
Y152175D01*
Y152312D01*
Y152449D01*
X330819D01*
Y152587D01*
X330681D01*
Y152724D01*
X330407D01*
Y152861D01*
D02*
G37*
G36*
X301158D02*
X282208D01*
Y152724D01*
X281522D01*
Y152587D01*
X281110D01*
Y152449D01*
X280972D01*
Y152312D01*
X280835D01*
Y152175D01*
X280698D01*
Y152037D01*
X280560D01*
Y151900D01*
X280423D01*
Y151763D01*
X280286D01*
Y151625D01*
X280149D01*
Y151488D01*
X280011D01*
Y151351D01*
X279874D01*
Y151213D01*
X279736D01*
Y151076D01*
X279599D01*
Y150939D01*
X279462D01*
Y150801D01*
X279324D01*
Y150664D01*
X279187D01*
Y150527D01*
X279050D01*
Y150389D01*
X278913D01*
Y150252D01*
X278775D01*
Y150115D01*
X278638D01*
Y149978D01*
X278501D01*
Y149840D01*
X278363D01*
Y149703D01*
X278226D01*
Y149566D01*
X278089D01*
Y149428D01*
X277951D01*
Y149291D01*
X277814D01*
Y149154D01*
X277677D01*
Y149016D01*
X277539D01*
Y148879D01*
X277402D01*
Y148742D01*
X277265D01*
Y148604D01*
X277127D01*
Y148467D01*
X276990D01*
Y148330D01*
Y148192D01*
X276853D01*
Y148055D01*
Y147918D01*
Y147781D01*
Y147643D01*
X276716D01*
Y147506D01*
Y147368D01*
Y147231D01*
Y147094D01*
Y146957D01*
Y146819D01*
Y146682D01*
Y146545D01*
Y146407D01*
Y146270D01*
Y146133D01*
Y145995D01*
Y145858D01*
Y145721D01*
Y145583D01*
Y145446D01*
Y145309D01*
Y145171D01*
Y145034D01*
Y144897D01*
Y144760D01*
Y144622D01*
Y144485D01*
Y144347D01*
Y144210D01*
Y144073D01*
Y143936D01*
Y143798D01*
Y143661D01*
Y143524D01*
Y143386D01*
Y143249D01*
Y143112D01*
Y142974D01*
Y142837D01*
Y142700D01*
Y142562D01*
Y142425D01*
Y142288D01*
Y142150D01*
Y142013D01*
Y141876D01*
Y141739D01*
Y141601D01*
Y141464D01*
Y141327D01*
Y141189D01*
Y141052D01*
Y140915D01*
Y140777D01*
Y140640D01*
Y140503D01*
Y140365D01*
Y140228D01*
Y140091D01*
Y139953D01*
Y139816D01*
Y139679D01*
Y139541D01*
Y139404D01*
Y139267D01*
Y139129D01*
Y138992D01*
Y138855D01*
Y138717D01*
Y138580D01*
Y138443D01*
Y138306D01*
Y138168D01*
Y138031D01*
Y137894D01*
Y137756D01*
Y137619D01*
Y137482D01*
Y137344D01*
Y137207D01*
Y137070D01*
Y136932D01*
Y136795D01*
Y136658D01*
Y136520D01*
Y136383D01*
Y136246D01*
Y136109D01*
Y135971D01*
Y135834D01*
Y135696D01*
Y135559D01*
Y135422D01*
Y135285D01*
Y135147D01*
Y135010D01*
Y134873D01*
Y134735D01*
Y134598D01*
Y134461D01*
Y134323D01*
Y134186D01*
Y134049D01*
Y133911D01*
Y133774D01*
Y133637D01*
Y133499D01*
Y133362D01*
Y133225D01*
Y133088D01*
Y132950D01*
Y132813D01*
Y132676D01*
Y132538D01*
Y132401D01*
Y132264D01*
Y132126D01*
Y131989D01*
Y131852D01*
Y131714D01*
Y131577D01*
Y131440D01*
Y131302D01*
Y131165D01*
Y131028D01*
Y130890D01*
Y130753D01*
Y130616D01*
Y130478D01*
Y130341D01*
Y130204D01*
Y130066D01*
Y129929D01*
Y129792D01*
Y129655D01*
Y129517D01*
Y129380D01*
Y129243D01*
Y129105D01*
Y128968D01*
Y128831D01*
Y128693D01*
Y128556D01*
Y128419D01*
Y128281D01*
Y128144D01*
X276853D01*
Y128007D01*
Y127869D01*
Y127732D01*
Y127595D01*
X276990D01*
Y127458D01*
Y127320D01*
Y127183D01*
X277127D01*
Y127045D01*
X277265D01*
Y126908D01*
X277402D01*
Y126771D01*
X277539D01*
Y126634D01*
X277677D01*
Y126496D01*
X277814D01*
Y126359D01*
X277951D01*
Y126222D01*
X278089D01*
Y126084D01*
X278226D01*
Y125947D01*
X278363D01*
Y125810D01*
X278501D01*
Y125672D01*
X278638D01*
Y125535D01*
X278775D01*
Y125398D01*
X278913D01*
Y125260D01*
X279050D01*
Y125123D01*
X279187D01*
Y124986D01*
X279324D01*
Y124848D01*
X279462D01*
Y124711D01*
X279599D01*
Y124574D01*
X279736D01*
Y124437D01*
X279874D01*
Y124299D01*
X280011D01*
Y124162D01*
X280149D01*
Y124024D01*
X280286D01*
Y123887D01*
X280423D01*
Y123750D01*
X280560D01*
Y123613D01*
X280698D01*
Y123475D01*
X280835D01*
Y123338D01*
X280972D01*
Y123201D01*
X281247D01*
Y123063D01*
X281796D01*
Y122926D01*
X301433D01*
Y123063D01*
X301570D01*
Y123201D01*
X301707D01*
Y123338D01*
X301845D01*
Y123475D01*
Y123613D01*
Y123750D01*
Y123887D01*
Y124024D01*
Y124162D01*
Y124299D01*
Y124437D01*
Y124574D01*
Y124711D01*
Y124848D01*
Y124986D01*
Y125123D01*
Y125260D01*
Y125398D01*
Y125535D01*
Y125672D01*
Y125810D01*
Y125947D01*
Y126084D01*
Y126222D01*
Y126359D01*
Y126496D01*
Y126634D01*
Y126771D01*
Y126908D01*
Y127045D01*
Y127183D01*
Y127320D01*
Y127458D01*
Y127595D01*
Y127732D01*
Y127869D01*
Y128007D01*
Y128144D01*
Y128281D01*
Y128419D01*
Y128556D01*
Y128693D01*
Y128831D01*
Y128968D01*
Y129105D01*
Y129243D01*
Y129380D01*
Y129517D01*
Y129655D01*
Y129792D01*
Y129929D01*
Y130066D01*
Y130204D01*
Y130341D01*
Y130478D01*
Y130616D01*
Y130753D01*
Y130890D01*
Y131028D01*
Y131165D01*
Y131302D01*
Y131440D01*
Y131577D01*
Y131714D01*
Y131852D01*
Y131989D01*
Y132126D01*
Y132264D01*
Y132401D01*
Y132538D01*
Y132676D01*
Y132813D01*
Y132950D01*
Y133088D01*
Y133225D01*
Y133362D01*
Y133499D01*
Y133637D01*
Y133774D01*
Y133911D01*
Y134049D01*
Y134186D01*
Y134323D01*
Y134461D01*
Y134598D01*
Y134735D01*
Y134873D01*
Y135010D01*
Y135147D01*
Y135285D01*
Y135422D01*
Y135559D01*
Y135696D01*
Y135834D01*
Y135971D01*
Y136109D01*
Y136246D01*
Y136383D01*
Y136520D01*
Y136658D01*
Y136795D01*
Y136932D01*
Y137070D01*
Y137207D01*
Y137344D01*
Y137482D01*
Y137619D01*
Y137756D01*
Y137894D01*
Y138031D01*
Y138168D01*
Y138306D01*
Y138443D01*
Y138580D01*
Y138717D01*
Y138855D01*
Y138992D01*
Y139129D01*
Y139267D01*
Y139404D01*
Y139541D01*
Y139679D01*
Y139816D01*
Y139953D01*
Y140091D01*
Y140228D01*
Y140365D01*
Y140503D01*
Y140640D01*
Y140777D01*
Y140915D01*
Y141052D01*
Y141189D01*
Y141327D01*
Y141464D01*
Y141601D01*
Y141739D01*
Y141876D01*
Y142013D01*
Y142150D01*
Y142288D01*
Y142425D01*
Y142562D01*
Y142700D01*
Y142837D01*
Y142974D01*
Y143112D01*
Y143249D01*
Y143386D01*
Y143524D01*
Y143661D01*
Y143798D01*
Y143936D01*
Y144073D01*
Y144210D01*
Y144347D01*
Y144485D01*
Y144622D01*
Y144760D01*
Y144897D01*
Y145034D01*
Y145171D01*
Y145309D01*
Y145446D01*
Y145583D01*
Y145721D01*
Y145858D01*
Y145995D01*
Y146133D01*
Y146270D01*
Y146407D01*
Y146545D01*
Y146682D01*
Y146819D01*
Y146957D01*
Y147094D01*
Y147231D01*
Y147368D01*
Y147506D01*
Y147643D01*
Y147781D01*
Y147918D01*
Y148055D01*
Y148192D01*
Y148330D01*
Y148467D01*
Y148604D01*
Y148742D01*
Y148879D01*
Y149016D01*
Y149154D01*
Y149291D01*
Y149428D01*
Y149566D01*
Y149703D01*
Y149840D01*
Y149978D01*
Y150115D01*
Y150252D01*
Y150389D01*
Y150527D01*
Y150664D01*
Y150801D01*
Y150939D01*
Y151076D01*
Y151213D01*
Y151351D01*
Y151488D01*
Y151625D01*
Y151763D01*
Y151900D01*
Y152037D01*
Y152175D01*
Y152312D01*
X301707D01*
Y152449D01*
X301570D01*
Y152587D01*
X301433D01*
Y152724D01*
X301158D01*
Y152861D01*
D02*
G37*
G36*
X399615Y152724D02*
X397967D01*
Y152587D01*
Y152449D01*
Y152312D01*
Y152175D01*
Y152037D01*
Y151900D01*
X397830D01*
Y151763D01*
Y151625D01*
Y151488D01*
Y151351D01*
Y151213D01*
Y151076D01*
Y150939D01*
Y150801D01*
Y150664D01*
Y150527D01*
Y150389D01*
Y150252D01*
Y150115D01*
Y149978D01*
Y149840D01*
Y149703D01*
X397692D01*
Y149566D01*
Y149428D01*
Y149291D01*
Y149154D01*
Y149016D01*
Y148879D01*
Y148742D01*
Y148604D01*
Y148467D01*
Y148330D01*
X397555D01*
Y148192D01*
Y148055D01*
Y147918D01*
Y147781D01*
Y147643D01*
Y147506D01*
Y147368D01*
Y147231D01*
X397418D01*
Y147094D01*
Y146957D01*
Y146819D01*
Y146682D01*
Y146545D01*
Y146407D01*
Y146270D01*
X397280D01*
Y146133D01*
Y145995D01*
Y145858D01*
Y145721D01*
Y145583D01*
Y145446D01*
X397143D01*
Y145309D01*
Y145171D01*
Y145034D01*
Y144897D01*
Y144760D01*
X397006D01*
Y144622D01*
Y144485D01*
Y144347D01*
Y144210D01*
Y144073D01*
X396868D01*
Y143936D01*
Y143798D01*
Y143661D01*
Y143524D01*
Y143386D01*
X396731D01*
Y143249D01*
Y143112D01*
Y142974D01*
Y142837D01*
Y142700D01*
X396594D01*
Y142562D01*
Y142425D01*
Y142288D01*
Y142150D01*
X396456D01*
Y142013D01*
Y141876D01*
Y141739D01*
Y141601D01*
X396319D01*
Y141464D01*
Y141327D01*
Y141189D01*
Y141052D01*
X396182D01*
Y140915D01*
Y140777D01*
Y140640D01*
Y140503D01*
X396044D01*
Y140365D01*
Y140228D01*
Y140091D01*
X395907D01*
Y139953D01*
Y139816D01*
Y139679D01*
Y139541D01*
X395770D01*
Y139404D01*
Y139267D01*
Y139129D01*
X395633D01*
Y138992D01*
Y138855D01*
Y138717D01*
X395495D01*
Y138580D01*
Y138443D01*
Y138306D01*
X395358D01*
Y138168D01*
Y138031D01*
Y137894D01*
X395220D01*
Y137756D01*
Y137619D01*
Y137482D01*
X395083D01*
Y137344D01*
Y137207D01*
Y137070D01*
X394946D01*
Y136932D01*
Y136795D01*
Y136658D01*
X394809D01*
Y136520D01*
Y136383D01*
X394671D01*
Y136246D01*
Y136109D01*
Y135971D01*
X394534D01*
Y135834D01*
Y135696D01*
Y135559D01*
X394397D01*
Y135422D01*
Y135285D01*
X394259D01*
Y135147D01*
Y135010D01*
Y134873D01*
X394122D01*
Y134735D01*
Y134598D01*
X393985D01*
Y134461D01*
Y134323D01*
X393847D01*
Y134186D01*
Y134049D01*
Y133911D01*
X393710D01*
Y133774D01*
Y133637D01*
X393573D01*
Y133499D01*
Y133362D01*
X393435D01*
Y133225D01*
Y133088D01*
Y132950D01*
X393298D01*
Y132813D01*
Y132676D01*
X393161D01*
Y132538D01*
Y132401D01*
X393023D01*
Y132264D01*
Y132126D01*
X392886D01*
Y131989D01*
Y131852D01*
X392749D01*
Y131714D01*
Y131577D01*
X392612D01*
Y131440D01*
Y131302D01*
X392474D01*
Y131165D01*
Y131028D01*
X392337D01*
Y130890D01*
Y130753D01*
X392200D01*
Y130616D01*
Y130478D01*
X392062D01*
Y130341D01*
Y130204D01*
X391925D01*
Y130066D01*
Y129929D01*
X391788D01*
Y129792D01*
Y129655D01*
X391650D01*
Y129517D01*
X391513D01*
Y129380D01*
Y129243D01*
X391376D01*
Y129105D01*
Y128968D01*
X391238D01*
Y128831D01*
Y128693D01*
X391101D01*
Y128556D01*
X390964D01*
Y128419D01*
Y128281D01*
X390826D01*
Y128144D01*
Y128007D01*
X390689D01*
Y127869D01*
Y127732D01*
X390552D01*
Y127595D01*
X390414D01*
Y127458D01*
Y127320D01*
X390277D01*
Y127183D01*
X390140D01*
Y127045D01*
Y126908D01*
X390003D01*
Y126771D01*
Y126634D01*
X389865D01*
Y126496D01*
X389728D01*
Y126359D01*
Y126222D01*
X389590D01*
Y126084D01*
X389453D01*
Y125947D01*
Y125810D01*
X389316D01*
Y125672D01*
X389179D01*
Y125535D01*
Y125398D01*
X389041D01*
Y125260D01*
X388904D01*
Y125123D01*
Y124986D01*
X388767D01*
Y124848D01*
X388629D01*
Y124711D01*
Y124574D01*
X388492D01*
Y124437D01*
X388355D01*
Y124299D01*
X388217D01*
Y124162D01*
Y124024D01*
X388080D01*
Y123887D01*
X387943D01*
Y123750D01*
X387805D01*
Y123613D01*
Y123475D01*
X387668D01*
Y123338D01*
X387531D01*
Y123201D01*
X387393D01*
Y123063D01*
Y122926D01*
X387256D01*
Y122789D01*
X387119D01*
Y122651D01*
X386982D01*
Y122514D01*
Y122377D01*
X386844D01*
Y122239D01*
X386707D01*
Y122102D01*
X386570D01*
Y121965D01*
X386432D01*
Y121827D01*
Y121690D01*
X386295D01*
Y121553D01*
X386158D01*
Y121416D01*
X386020D01*
Y121278D01*
X385883D01*
Y121141D01*
X385746D01*
Y121004D01*
Y120866D01*
X385608D01*
Y120729D01*
X385471D01*
Y120592D01*
X385334D01*
Y120454D01*
X385196D01*
Y120317D01*
X385059D01*
Y120180D01*
X384922D01*
Y120042D01*
X384784D01*
Y119905D01*
Y119768D01*
X384647D01*
Y119630D01*
X384510D01*
Y119493D01*
X384372D01*
Y119356D01*
X384235D01*
Y119218D01*
X384098D01*
Y119081D01*
X383960D01*
Y118944D01*
X383823D01*
Y118806D01*
X383686D01*
Y118669D01*
X383549D01*
Y118532D01*
X383411D01*
Y118394D01*
X383274D01*
Y118257D01*
X383137D01*
Y118120D01*
X382999D01*
Y117983D01*
X382862D01*
Y117845D01*
X382725D01*
Y117708D01*
X382587D01*
Y117571D01*
X382450D01*
Y117433D01*
X382313D01*
Y117296D01*
X382175D01*
Y117159D01*
X382038D01*
Y117021D01*
X381901D01*
Y116884D01*
X381763D01*
Y116747D01*
X381626D01*
Y116609D01*
X381489D01*
Y116472D01*
X381352D01*
Y116335D01*
X381214D01*
Y116198D01*
X381077D01*
Y116060D01*
X380802D01*
Y115923D01*
X380665D01*
Y115786D01*
X380528D01*
Y115648D01*
X380390D01*
Y115511D01*
X380253D01*
Y115373D01*
X380116D01*
Y115236D01*
X379978D01*
Y115099D01*
X379704D01*
Y114962D01*
X379566D01*
Y114824D01*
X379429D01*
Y114687D01*
X379292D01*
Y114550D01*
X379154D01*
Y114412D01*
X378880D01*
Y114275D01*
X378742D01*
Y114138D01*
X378605D01*
Y114000D01*
X378468D01*
Y113863D01*
X378193D01*
Y113726D01*
X378056D01*
Y113588D01*
X377919D01*
Y113451D01*
X377644D01*
Y113314D01*
X377507D01*
Y113176D01*
X377369D01*
Y113039D01*
X377095D01*
Y112902D01*
X376957D01*
Y112765D01*
X376820D01*
Y112627D01*
X376545D01*
Y112490D01*
X376408D01*
Y112353D01*
X376271D01*
Y112215D01*
X375996D01*
Y112078D01*
X375859D01*
Y111941D01*
X375584D01*
Y111803D01*
X375447D01*
Y111666D01*
X375172D01*
Y111529D01*
X375035D01*
Y111391D01*
X374760D01*
Y111254D01*
X374623D01*
Y111117D01*
X374348D01*
Y110979D01*
X374211D01*
Y110842D01*
X373936D01*
Y110705D01*
X373662D01*
Y110567D01*
X373524D01*
Y110430D01*
X373250D01*
Y110293D01*
X373112D01*
Y110155D01*
X372838D01*
Y110018D01*
X372563D01*
Y109881D01*
X372426D01*
Y109743D01*
X372151D01*
Y109606D01*
X371876D01*
Y109469D01*
X371602D01*
Y109332D01*
X371327D01*
Y109194D01*
X371190D01*
Y109057D01*
X370915D01*
Y108920D01*
X370641D01*
Y108782D01*
X370366D01*
Y108645D01*
X370091D01*
Y108508D01*
X369817D01*
Y108370D01*
X369542D01*
Y108233D01*
X369268D01*
Y108096D01*
X368993D01*
Y107958D01*
X368718D01*
Y107821D01*
X368444D01*
Y107684D01*
X368169D01*
Y107546D01*
X367894D01*
Y107409D01*
X367482D01*
Y107272D01*
X367208D01*
Y107135D01*
X366933D01*
Y106997D01*
X366659D01*
Y106860D01*
X366246D01*
Y106722D01*
X365972D01*
Y106585D01*
X365560D01*
Y106448D01*
X365285D01*
Y106311D01*
X364873D01*
Y106173D01*
X364599D01*
Y106036D01*
X364187D01*
Y105899D01*
X363775D01*
Y105761D01*
X363363D01*
Y105624D01*
X362951D01*
Y105487D01*
X362539D01*
Y105349D01*
X362127D01*
Y105212D01*
X361715D01*
Y105075D01*
X361303D01*
Y104937D01*
X360754D01*
Y104800D01*
X360342D01*
Y104663D01*
X359793D01*
Y104525D01*
X359243D01*
Y104388D01*
X358694D01*
Y104251D01*
X358145D01*
Y104114D01*
X357595D01*
Y103976D01*
X356909D01*
Y103839D01*
X356222D01*
Y103701D01*
X355398D01*
Y103564D01*
X354575D01*
Y103427D01*
X353613D01*
Y103290D01*
X352515D01*
Y103152D01*
X351279D01*
Y103015D01*
X349219D01*
Y102878D01*
X343864D01*
Y103015D01*
X343589D01*
Y102878D01*
X343452D01*
Y103015D01*
X341941D01*
Y103152D01*
X340294D01*
Y103290D01*
X339470D01*
Y103427D01*
X338508D01*
Y103564D01*
X337685D01*
Y103701D01*
X336861D01*
Y103839D01*
X336174D01*
Y103976D01*
X335625D01*
Y104114D01*
X334938D01*
Y104251D01*
X334389D01*
Y104388D01*
X333840D01*
Y104525D01*
X333290D01*
Y104663D01*
X332741D01*
Y104800D01*
X332329D01*
Y104937D01*
X331780D01*
Y105075D01*
X331368D01*
Y105212D01*
X330956D01*
Y105349D01*
X330544D01*
Y105487D01*
X330132D01*
Y105624D01*
X329720D01*
Y105761D01*
X329308D01*
Y105899D01*
X328896D01*
Y106036D01*
X328621D01*
Y106173D01*
X328210D01*
Y106311D01*
X327798D01*
Y106448D01*
X327523D01*
Y106585D01*
X327111D01*
Y106722D01*
X326836D01*
Y106860D01*
X326562D01*
Y106997D01*
X326150D01*
Y107135D01*
X325875D01*
Y107272D01*
X325463D01*
Y107409D01*
X325189D01*
Y107546D01*
X324914D01*
Y107684D01*
X324639D01*
Y107821D01*
X324365D01*
Y107958D01*
X324090D01*
Y108096D01*
X323815D01*
Y108233D01*
X323541D01*
Y108370D01*
X323266D01*
Y108508D01*
X322991D01*
Y108645D01*
X322717D01*
Y108782D01*
X322442D01*
Y108920D01*
X322168D01*
Y109057D01*
X321893D01*
Y109194D01*
X321756D01*
Y109332D01*
X321481D01*
Y109469D01*
X321206D01*
Y109606D01*
X320932D01*
Y109743D01*
X320794D01*
Y109881D01*
X320520D01*
Y110018D01*
X320245D01*
Y110155D01*
X320108D01*
Y110293D01*
X319833D01*
Y110430D01*
X319559D01*
Y110567D01*
X319421D01*
Y110705D01*
X319147D01*
Y110842D01*
X318872D01*
Y110979D01*
X318735D01*
Y111117D01*
X318460D01*
Y111254D01*
X318323D01*
Y111391D01*
X318048D01*
Y111529D01*
X317911D01*
Y111666D01*
X317636D01*
Y111803D01*
X317499D01*
Y111941D01*
X317224D01*
Y112078D01*
X317087D01*
Y112215D01*
X316950D01*
Y112353D01*
X316675D01*
Y112490D01*
X316538D01*
Y112627D01*
X316263D01*
Y112765D01*
X316126D01*
Y112902D01*
X315988D01*
Y113039D01*
X315714D01*
Y113176D01*
X315576D01*
Y113314D01*
X315439D01*
Y113451D01*
X315164D01*
Y113588D01*
X315027D01*
Y113726D01*
X314890D01*
Y113863D01*
X314753D01*
Y114000D01*
X314478D01*
Y114138D01*
X314340D01*
Y114275D01*
X314203D01*
Y114412D01*
X314066D01*
Y114550D01*
X313791D01*
Y114687D01*
X313654D01*
Y114824D01*
X313517D01*
Y114962D01*
X313379D01*
Y115099D01*
X313242D01*
Y115236D01*
X312967D01*
Y115373D01*
X312830D01*
Y115511D01*
X312693D01*
Y115648D01*
X312555D01*
Y115786D01*
X312418D01*
Y115923D01*
X312281D01*
Y116060D01*
X312143D01*
Y116198D01*
X311869D01*
Y116335D01*
X311731D01*
Y116472D01*
X311594D01*
Y116609D01*
X311457D01*
Y116747D01*
X311320D01*
Y116884D01*
X311182D01*
Y117021D01*
X311045D01*
Y117159D01*
X310908D01*
Y117296D01*
X310770D01*
Y117433D01*
X310633D01*
Y117571D01*
X310496D01*
Y117708D01*
X310358D01*
Y117845D01*
X310221D01*
Y117983D01*
X310084D01*
Y118120D01*
X309946D01*
Y118257D01*
X309809D01*
Y118394D01*
X309672D01*
Y118532D01*
X309534D01*
Y118669D01*
X309397D01*
Y118806D01*
X309260D01*
Y118944D01*
X309122D01*
Y119081D01*
X308985D01*
Y119218D01*
X308848D01*
Y119356D01*
X308710D01*
Y119493D01*
X308573D01*
Y119630D01*
X308436D01*
Y119768D01*
Y119905D01*
X308298D01*
Y120042D01*
X308161D01*
Y120180D01*
X305964D01*
Y120042D01*
X306101D01*
Y119905D01*
Y119768D01*
X306239D01*
Y119630D01*
X306376D01*
Y119493D01*
X306513D01*
Y119356D01*
X306651D01*
Y119218D01*
X306788D01*
Y119081D01*
X306925D01*
Y118944D01*
X307063D01*
Y118806D01*
Y118669D01*
X307200D01*
Y118532D01*
X307337D01*
Y118394D01*
X307475D01*
Y118257D01*
X307612D01*
Y118120D01*
X307749D01*
Y117983D01*
X307887D01*
Y117845D01*
X308024D01*
Y117708D01*
X308161D01*
Y117571D01*
X308298D01*
Y117433D01*
X308436D01*
Y117296D01*
X308573D01*
Y117159D01*
X308710D01*
Y117021D01*
X308848D01*
Y116884D01*
X308985D01*
Y116747D01*
X309122D01*
Y116609D01*
X309260D01*
Y116472D01*
X309397D01*
Y116335D01*
X309534D01*
Y116198D01*
X309672D01*
Y116060D01*
X309809D01*
Y115923D01*
X309946D01*
Y115786D01*
X310084D01*
Y115648D01*
X310221D01*
Y115511D01*
X310358D01*
Y115373D01*
X310496D01*
Y115236D01*
X310633D01*
Y115099D01*
X310770D01*
Y114962D01*
X310908D01*
Y114824D01*
X311182D01*
Y114687D01*
X311320D01*
Y114550D01*
X311457D01*
Y114412D01*
X311594D01*
Y114275D01*
X311731D01*
Y114138D01*
X311869D01*
Y114000D01*
X312006D01*
Y113863D01*
X312281D01*
Y113726D01*
X312418D01*
Y113588D01*
X312555D01*
Y113451D01*
X312693D01*
Y113314D01*
X312830D01*
Y113176D01*
X313105D01*
Y113039D01*
X313242D01*
Y112902D01*
X313379D01*
Y112765D01*
X313517D01*
Y112627D01*
X313791D01*
Y112490D01*
X313929D01*
Y112353D01*
X314066D01*
Y112215D01*
X314203D01*
Y112078D01*
X314478D01*
Y111941D01*
X314615D01*
Y111803D01*
X314753D01*
Y111666D01*
X315027D01*
Y111529D01*
X315164D01*
Y111391D01*
X315302D01*
Y111254D01*
X315576D01*
Y111117D01*
X315714D01*
Y110979D01*
X315988D01*
Y110842D01*
X316126D01*
Y110705D01*
X316400D01*
Y110567D01*
X316538D01*
Y110430D01*
X316675D01*
Y110293D01*
X316950D01*
Y110155D01*
X317087D01*
Y110018D01*
X317362D01*
Y109881D01*
X317499D01*
Y109743D01*
X317773D01*
Y109606D01*
X318048D01*
Y109469D01*
X318185D01*
Y109332D01*
X318460D01*
Y109194D01*
X318597D01*
Y109057D01*
X318872D01*
Y108920D01*
X319147D01*
Y108782D01*
X319284D01*
Y108645D01*
X319559D01*
Y108508D01*
X319833D01*
Y108370D01*
X319970D01*
Y108233D01*
X320245D01*
Y108096D01*
X320520D01*
Y107958D01*
X320794D01*
Y107821D01*
X320932D01*
Y107684D01*
X321206D01*
Y107546D01*
X321481D01*
Y107409D01*
X321756D01*
Y107272D01*
X322030D01*
Y107135D01*
X322305D01*
Y106997D01*
X322580D01*
Y106860D01*
X322854D01*
Y106722D01*
X323129D01*
Y106585D01*
X323404D01*
Y106448D01*
X323678D01*
Y106311D01*
X323953D01*
Y106173D01*
X324227D01*
Y106036D01*
X324502D01*
Y105899D01*
X324777D01*
Y105761D01*
X325189D01*
Y105624D01*
X325463D01*
Y105487D01*
X325738D01*
Y105349D01*
X326150D01*
Y105212D01*
X326424D01*
Y105075D01*
X326836D01*
Y104937D01*
X327111D01*
Y104800D01*
X327523D01*
Y104663D01*
X327798D01*
Y104525D01*
X328210D01*
Y104388D01*
X328621D01*
Y104251D01*
X329034D01*
Y104114D01*
X329445D01*
Y103976D01*
X329857D01*
Y103839D01*
X330269D01*
Y103701D01*
X330681D01*
Y103564D01*
X331093D01*
Y103427D01*
X331505D01*
Y103290D01*
X332054D01*
Y103152D01*
X332466D01*
Y103015D01*
X333016D01*
Y102878D01*
X333565D01*
Y102740D01*
X334114D01*
Y102603D01*
X334801D01*
Y102466D01*
X335350D01*
Y102328D01*
X335899D01*
Y102191D01*
X336723D01*
Y102054D01*
X337410D01*
Y101916D01*
X338234D01*
Y101779D01*
X339195D01*
Y101642D01*
X340294D01*
Y101504D01*
X341529D01*
Y101367D01*
X343315D01*
Y101230D01*
X349906D01*
Y101367D01*
X351554D01*
Y101504D01*
X352927D01*
Y101642D01*
X353888D01*
Y101779D01*
X354849D01*
Y101916D01*
X355673D01*
Y102054D01*
X356497D01*
Y102191D01*
X357184D01*
Y102328D01*
X357733D01*
Y102466D01*
X358419D01*
Y102603D01*
X358969D01*
Y102740D01*
X359518D01*
Y102878D01*
X360067D01*
Y103015D01*
X360616D01*
Y103152D01*
X361029D01*
Y103290D01*
X361578D01*
Y103427D01*
X361990D01*
Y103564D01*
X362402D01*
Y103701D01*
X362951D01*
Y103839D01*
X363363D01*
Y103976D01*
X363775D01*
Y104114D01*
X364049D01*
Y104251D01*
X364461D01*
Y104388D01*
X364873D01*
Y104525D01*
X365285D01*
Y104663D01*
X365560D01*
Y104800D01*
X365972D01*
Y104937D01*
X366246D01*
Y105075D01*
X366659D01*
Y105212D01*
X366933D01*
Y105349D01*
X367345D01*
Y105487D01*
X367620D01*
Y105624D01*
X367894D01*
Y105761D01*
X368306D01*
Y105899D01*
X368581D01*
Y106036D01*
X368856D01*
Y106173D01*
X369130D01*
Y106311D01*
X369405D01*
Y106448D01*
X369679D01*
Y106585D01*
X369954D01*
Y106722D01*
X370229D01*
Y106860D01*
X370503D01*
Y106997D01*
X370778D01*
Y107135D01*
X371053D01*
Y107272D01*
X371327D01*
Y107409D01*
X371602D01*
Y107546D01*
X371876D01*
Y107684D01*
X372151D01*
Y107821D01*
X372426D01*
Y107958D01*
X372563D01*
Y108096D01*
X372838D01*
Y108233D01*
X373112D01*
Y108370D01*
X373387D01*
Y108508D01*
X373524D01*
Y108645D01*
X373799D01*
Y108782D01*
X374074D01*
Y108920D01*
X374211D01*
Y109057D01*
X374486D01*
Y109194D01*
X374623D01*
Y109332D01*
X374897D01*
Y109469D01*
X375172D01*
Y109606D01*
X375309D01*
Y109743D01*
X375584D01*
Y109881D01*
X375721D01*
Y110018D01*
X375996D01*
Y110155D01*
X376133D01*
Y110293D01*
X376408D01*
Y110430D01*
X376545D01*
Y110567D01*
X376820D01*
Y110705D01*
X376957D01*
Y110842D01*
X377095D01*
Y110979D01*
X377369D01*
Y111117D01*
X377507D01*
Y111254D01*
X377781D01*
Y111391D01*
X377919D01*
Y111529D01*
X378056D01*
Y111666D01*
X378330D01*
Y111803D01*
X378468D01*
Y111941D01*
X378605D01*
Y112078D01*
X378880D01*
Y112215D01*
X379017D01*
Y112353D01*
X379154D01*
Y112490D01*
X379429D01*
Y112627D01*
X379566D01*
Y112765D01*
X379704D01*
Y112902D01*
X379841D01*
Y113039D01*
X380116D01*
Y113176D01*
X380253D01*
Y113314D01*
X380390D01*
Y113451D01*
X380528D01*
Y113588D01*
X380665D01*
Y113726D01*
X380939D01*
Y113863D01*
X381077D01*
Y114000D01*
X381214D01*
Y114138D01*
X381352D01*
Y114275D01*
X381489D01*
Y114412D01*
X381626D01*
Y114550D01*
X381763D01*
Y114687D01*
X382038D01*
Y114824D01*
X382175D01*
Y114962D01*
X382313D01*
Y115099D01*
X382450D01*
Y115236D01*
X382587D01*
Y115373D01*
X382725D01*
Y115511D01*
X382862D01*
Y115648D01*
X382999D01*
Y115786D01*
X383137D01*
Y115923D01*
X383274D01*
Y116060D01*
X383411D01*
Y116198D01*
X383549D01*
Y116335D01*
X383686D01*
Y116472D01*
X383823D01*
Y116609D01*
X383960D01*
Y116747D01*
X384098D01*
Y116884D01*
X384235D01*
Y117021D01*
X384372D01*
Y117159D01*
X384510D01*
Y117296D01*
X384647D01*
Y117433D01*
X384784D01*
Y117571D01*
X384922D01*
Y117708D01*
X385059D01*
Y117845D01*
X385196D01*
Y117983D01*
X385334D01*
Y118120D01*
X385471D01*
Y118257D01*
X385608D01*
Y118394D01*
X385746D01*
Y118532D01*
X385883D01*
Y118669D01*
X386020D01*
Y118806D01*
X386158D01*
Y118944D01*
Y119081D01*
X386295D01*
Y119218D01*
X386432D01*
Y119356D01*
X386570D01*
Y119493D01*
X386707D01*
Y119630D01*
X386844D01*
Y119768D01*
X386982D01*
Y119905D01*
X387119D01*
Y120042D01*
Y120180D01*
X387256D01*
Y120317D01*
X387393D01*
Y120454D01*
X387531D01*
Y120592D01*
X387668D01*
Y120729D01*
Y120866D01*
X387805D01*
Y121004D01*
X387943D01*
Y121141D01*
X388080D01*
Y121278D01*
X388217D01*
Y121416D01*
Y121553D01*
X388355D01*
Y121690D01*
X388492D01*
Y121827D01*
X388629D01*
Y121965D01*
X388767D01*
Y122102D01*
Y122239D01*
X388904D01*
Y122377D01*
X389041D01*
Y122514D01*
X389179D01*
Y122651D01*
Y122789D01*
X389316D01*
Y122926D01*
X389453D01*
Y123063D01*
X389590D01*
Y123201D01*
Y123338D01*
X389728D01*
Y123475D01*
X389865D01*
Y123613D01*
Y123750D01*
X390003D01*
Y123887D01*
X390140D01*
Y124024D01*
X390277D01*
Y124162D01*
Y124299D01*
X390414D01*
Y124437D01*
X390552D01*
Y124574D01*
Y124711D01*
X390689D01*
Y124848D01*
X390826D01*
Y124986D01*
Y125123D01*
X390964D01*
Y125260D01*
X391101D01*
Y125398D01*
Y125535D01*
X391238D01*
Y125672D01*
X391376D01*
Y125810D01*
Y125947D01*
X391513D01*
Y126084D01*
Y126222D01*
X391650D01*
Y126359D01*
X391788D01*
Y126496D01*
Y126634D01*
X391925D01*
Y126771D01*
X392062D01*
Y126908D01*
Y127045D01*
X392200D01*
Y127183D01*
Y127320D01*
X392337D01*
Y127458D01*
Y127595D01*
X392474D01*
Y127732D01*
X392612D01*
Y127869D01*
Y128007D01*
X392749D01*
Y128144D01*
Y128281D01*
X392886D01*
Y128419D01*
Y128556D01*
X393023D01*
Y128693D01*
Y128831D01*
X393161D01*
Y128968D01*
X393298D01*
Y129105D01*
Y129243D01*
X393435D01*
Y129380D01*
Y129517D01*
X393573D01*
Y129655D01*
Y129792D01*
X393710D01*
Y129929D01*
Y130066D01*
X393847D01*
Y130204D01*
Y130341D01*
X393985D01*
Y130478D01*
Y130616D01*
X394122D01*
Y130753D01*
Y130890D01*
X394259D01*
Y131028D01*
Y131165D01*
X394397D01*
Y131302D01*
Y131440D01*
X394534D01*
Y131577D01*
Y131714D01*
X394671D01*
Y131852D01*
Y131989D01*
X394809D01*
Y132126D01*
Y132264D01*
X394946D01*
Y132401D01*
Y132538D01*
X395083D01*
Y132676D01*
Y132813D01*
Y132950D01*
X395220D01*
Y133088D01*
Y133225D01*
X395358D01*
Y133362D01*
Y133499D01*
X395495D01*
Y133637D01*
Y133774D01*
Y133911D01*
X395633D01*
Y134049D01*
Y134186D01*
X395770D01*
Y134323D01*
Y134461D01*
Y134598D01*
X395907D01*
Y134735D01*
Y134873D01*
X396044D01*
Y135010D01*
Y135147D01*
Y135285D01*
X396182D01*
Y135422D01*
Y135559D01*
X396319D01*
Y135696D01*
Y135834D01*
Y135971D01*
X396456D01*
Y136109D01*
Y136246D01*
Y136383D01*
X396594D01*
Y136520D01*
Y136658D01*
Y136795D01*
X396731D01*
Y136932D01*
Y137070D01*
Y137207D01*
X396868D01*
Y137344D01*
Y137482D01*
Y137619D01*
X397006D01*
Y137756D01*
Y137894D01*
Y138031D01*
X397143D01*
Y138168D01*
Y138306D01*
Y138443D01*
X397280D01*
Y138580D01*
Y138717D01*
Y138855D01*
X397418D01*
Y138992D01*
Y139129D01*
Y139267D01*
X397555D01*
Y139404D01*
Y139541D01*
Y139679D01*
Y139816D01*
X397692D01*
Y139953D01*
Y140091D01*
Y140228D01*
X397830D01*
Y140365D01*
Y140503D01*
Y140640D01*
Y140777D01*
X397967D01*
Y140915D01*
Y141052D01*
Y141189D01*
Y141327D01*
X398104D01*
Y141464D01*
Y141601D01*
Y141739D01*
Y141876D01*
X398242D01*
Y142013D01*
Y142150D01*
Y142288D01*
Y142425D01*
X398379D01*
Y142562D01*
Y142700D01*
Y142837D01*
Y142974D01*
Y143112D01*
X398516D01*
Y143249D01*
Y143386D01*
Y143524D01*
Y143661D01*
Y143798D01*
X398653D01*
Y143936D01*
Y144073D01*
Y144210D01*
Y144347D01*
Y144485D01*
X398791D01*
Y144622D01*
Y144760D01*
Y144897D01*
Y145034D01*
Y145171D01*
X398928D01*
Y145309D01*
Y145446D01*
Y145583D01*
Y145721D01*
Y145858D01*
Y145995D01*
X399065D01*
Y146133D01*
Y146270D01*
Y146407D01*
Y146545D01*
Y146682D01*
Y146819D01*
Y146957D01*
X399203D01*
Y147094D01*
Y147231D01*
Y147368D01*
Y147506D01*
Y147643D01*
Y147781D01*
Y147918D01*
Y148055D01*
X399340D01*
Y148192D01*
Y148330D01*
Y148467D01*
Y148604D01*
Y148742D01*
Y148879D01*
Y149016D01*
Y149154D01*
Y149291D01*
Y149428D01*
X399477D01*
Y149566D01*
X399340D01*
Y149703D01*
X399477D01*
Y149840D01*
Y149978D01*
Y150115D01*
Y150252D01*
Y150389D01*
Y150527D01*
Y150664D01*
Y150801D01*
Y150939D01*
Y151076D01*
Y151213D01*
X399615D01*
Y151351D01*
Y151488D01*
Y151625D01*
Y151763D01*
Y151900D01*
Y152037D01*
Y152175D01*
Y152312D01*
Y152449D01*
Y152587D01*
Y152724D01*
D02*
G37*
%LPD*%
G36*
X323815Y145721D02*
Y145583D01*
Y145446D01*
Y145309D01*
Y145171D01*
Y145034D01*
Y144897D01*
Y144760D01*
Y144622D01*
Y144485D01*
Y144347D01*
Y144210D01*
Y144073D01*
Y143936D01*
Y143798D01*
Y143661D01*
Y143524D01*
Y143386D01*
Y143249D01*
Y143112D01*
Y142974D01*
Y142837D01*
Y142700D01*
Y142562D01*
Y142425D01*
Y142288D01*
Y142150D01*
Y142013D01*
Y141876D01*
Y141739D01*
Y141601D01*
Y141464D01*
Y141327D01*
Y141189D01*
Y141052D01*
Y140915D01*
Y140777D01*
Y140640D01*
Y140503D01*
Y140365D01*
Y140228D01*
Y140091D01*
Y139953D01*
Y139816D01*
Y139679D01*
Y139541D01*
Y139404D01*
Y139267D01*
Y139129D01*
Y138992D01*
Y138855D01*
Y138717D01*
Y138580D01*
X313517D01*
Y138717D01*
Y138855D01*
Y138992D01*
Y139129D01*
Y139267D01*
Y139404D01*
Y139541D01*
Y139679D01*
Y139816D01*
Y139953D01*
Y140091D01*
Y140228D01*
Y140365D01*
Y140503D01*
Y140640D01*
Y140777D01*
Y140915D01*
Y141052D01*
Y141189D01*
Y141327D01*
Y141464D01*
Y141601D01*
Y141739D01*
Y141876D01*
Y142013D01*
Y142150D01*
Y142288D01*
Y142425D01*
Y142562D01*
Y142700D01*
Y142837D01*
Y142974D01*
Y143112D01*
Y143249D01*
Y143386D01*
Y143524D01*
Y143661D01*
Y143798D01*
Y143936D01*
Y144073D01*
Y144210D01*
Y144347D01*
Y144485D01*
Y144622D01*
Y144760D01*
Y144897D01*
Y145034D01*
Y145171D01*
Y145309D01*
Y145446D01*
Y145583D01*
Y145721D01*
Y145858D01*
X323815D01*
Y145721D01*
D02*
G37*
G36*
X294155Y145446D02*
X294292D01*
Y145309D01*
Y145171D01*
Y145034D01*
Y144897D01*
Y144760D01*
Y144622D01*
Y144485D01*
Y144347D01*
Y144210D01*
Y144073D01*
Y143936D01*
Y143798D01*
Y143661D01*
Y143524D01*
Y143386D01*
Y143249D01*
Y143112D01*
Y142974D01*
Y142837D01*
Y142700D01*
Y142562D01*
Y142425D01*
Y142288D01*
Y142150D01*
Y142013D01*
Y141876D01*
Y141739D01*
Y141601D01*
Y141464D01*
Y141327D01*
Y141189D01*
Y141052D01*
Y140915D01*
Y140777D01*
Y140640D01*
Y140503D01*
Y140365D01*
Y140228D01*
Y140091D01*
Y139953D01*
Y139816D01*
Y139679D01*
Y139541D01*
Y139404D01*
Y139267D01*
Y139129D01*
Y138992D01*
Y138855D01*
Y138717D01*
Y138580D01*
Y138443D01*
Y138306D01*
Y138168D01*
Y138031D01*
Y137894D01*
Y137756D01*
Y137619D01*
Y137482D01*
Y137344D01*
Y137207D01*
Y137070D01*
Y136932D01*
Y136795D01*
Y136658D01*
Y136520D01*
Y136383D01*
Y136246D01*
Y136109D01*
Y135971D01*
Y135834D01*
Y135696D01*
Y135559D01*
Y135422D01*
Y135285D01*
Y135147D01*
Y135010D01*
Y134873D01*
Y134735D01*
Y134598D01*
Y134461D01*
Y134323D01*
Y134186D01*
Y134049D01*
Y133911D01*
Y133774D01*
Y133637D01*
Y133499D01*
Y133362D01*
Y133225D01*
Y133088D01*
Y132950D01*
Y132813D01*
Y132676D01*
Y132538D01*
Y132401D01*
Y132264D01*
Y132126D01*
Y131989D01*
Y131852D01*
Y131714D01*
Y131577D01*
Y131440D01*
Y131302D01*
Y131165D01*
Y131028D01*
Y130890D01*
Y130753D01*
Y130616D01*
Y130478D01*
Y130341D01*
Y130204D01*
X284268D01*
Y130341D01*
Y130478D01*
Y130616D01*
Y130753D01*
Y130890D01*
Y131028D01*
Y131165D01*
Y131302D01*
Y131440D01*
Y131577D01*
Y131714D01*
Y131852D01*
Y131989D01*
Y132126D01*
Y132264D01*
Y132401D01*
Y132538D01*
Y132676D01*
Y132813D01*
Y132950D01*
Y133088D01*
Y133225D01*
Y133362D01*
Y133499D01*
Y133637D01*
Y133774D01*
Y133911D01*
Y134049D01*
Y134186D01*
Y134323D01*
Y134461D01*
Y134598D01*
Y134735D01*
Y134873D01*
Y135010D01*
Y135147D01*
Y135285D01*
Y135422D01*
Y135559D01*
Y135696D01*
Y135834D01*
Y135971D01*
Y136109D01*
Y136246D01*
Y136383D01*
Y136520D01*
Y136658D01*
Y136795D01*
Y136932D01*
Y137070D01*
Y137207D01*
Y137344D01*
Y137482D01*
Y137619D01*
Y137756D01*
Y137894D01*
Y138031D01*
Y138168D01*
Y138306D01*
Y138443D01*
Y138580D01*
Y138717D01*
Y138855D01*
Y138992D01*
Y139129D01*
Y139267D01*
Y139404D01*
Y139541D01*
Y139679D01*
Y139816D01*
Y139953D01*
Y140091D01*
Y140228D01*
Y140365D01*
Y140503D01*
Y140640D01*
Y140777D01*
Y140915D01*
Y141052D01*
Y141189D01*
Y141327D01*
Y141464D01*
Y141601D01*
Y141739D01*
Y141876D01*
Y142013D01*
Y142150D01*
Y142288D01*
Y142425D01*
Y142562D01*
Y142700D01*
Y142837D01*
Y142974D01*
Y143112D01*
Y143249D01*
Y143386D01*
Y143524D01*
Y143661D01*
Y143798D01*
Y143936D01*
Y144073D01*
Y144210D01*
Y144347D01*
Y144485D01*
Y144622D01*
Y144760D01*
Y144897D01*
Y145034D01*
Y145171D01*
Y145309D01*
Y145446D01*
X284543D01*
Y145583D01*
X284680D01*
Y145446D01*
X284955D01*
Y145583D01*
X285092D01*
Y145446D01*
X294018D01*
Y145583D01*
X294155D01*
Y145446D01*
D02*
G37*
%LPC*%
G36*
X366576Y27762D02*
X366564D01*
X366576Y27317D01*
X366588Y27040D01*
X366600Y26799D01*
X366636Y26594D01*
X366672Y26426D01*
X366708Y26293D01*
X366732Y26197D01*
X366757Y26149D01*
X366769Y26125D01*
X366877Y25932D01*
X366997Y25776D01*
X367130Y25631D01*
X367262Y25511D01*
X367383Y25415D01*
X367479Y25354D01*
X367551Y25306D01*
X367563Y25294D01*
X367575D01*
X367780Y25198D01*
X367997Y25126D01*
X368201Y25065D01*
X368394Y25029D01*
X368563Y25005D01*
X368683Y24993D01*
X368803D01*
X369056Y25005D01*
X369273Y25041D01*
X369453Y25089D01*
X369610Y25150D01*
X369718Y25210D01*
X369803Y25258D01*
X369863Y25294D01*
X369875Y25306D01*
X369995Y25439D01*
X370079Y25571D01*
X370152Y25703D01*
X370188Y25824D01*
X370212Y25932D01*
X370224Y26028D01*
X370236Y26077D01*
Y26101D01*
X370224Y26221D01*
X370212Y26318D01*
X370188Y26414D01*
X370152Y26498D01*
X370128Y26570D01*
X370103Y26618D01*
X370092Y26655D01*
X370079Y26667D01*
X370007Y26763D01*
X369935Y26835D01*
X369851Y26907D01*
X369779Y26968D01*
X369706Y27004D01*
X369646Y27040D01*
X369610Y27064D01*
X369598D01*
X369465Y27112D01*
X369297Y27160D01*
X369128Y27196D01*
X368948Y27232D01*
X368791Y27269D01*
X368659Y27281D01*
X368611Y27293D01*
X368574Y27305D01*
X368538D01*
X368298Y27341D01*
X368081Y27377D01*
X367864Y27413D01*
X367672Y27449D01*
X367503Y27485D01*
X367334Y27534D01*
X367190Y27570D01*
X367057Y27606D01*
X366937Y27630D01*
X366841Y27666D01*
X366757Y27690D01*
X366684Y27714D01*
X366636Y27738D01*
X366600Y27750D01*
X366576Y27762D01*
D02*
G37*
G36*
X312747D02*
X312735D01*
X312747Y27317D01*
X312759Y27040D01*
X312771Y26799D01*
X312807Y26594D01*
X312843Y26426D01*
X312879Y26293D01*
X312903Y26197D01*
X312927Y26149D01*
X312939Y26125D01*
X313048Y25932D01*
X313168Y25776D01*
X313301Y25631D01*
X313433Y25511D01*
X313554Y25415D01*
X313650Y25354D01*
X313722Y25306D01*
X313734Y25294D01*
X313746D01*
X313951Y25198D01*
X314167Y25126D01*
X314372Y25065D01*
X314565Y25029D01*
X314733Y25005D01*
X314854Y24993D01*
X314974D01*
X315227Y25005D01*
X315444Y25041D01*
X315624Y25089D01*
X315781Y25150D01*
X315889Y25210D01*
X315973Y25258D01*
X316034Y25294D01*
X316046Y25306D01*
X316166Y25439D01*
X316250Y25571D01*
X316323Y25703D01*
X316359Y25824D01*
X316383Y25932D01*
X316395Y26028D01*
X316407Y26077D01*
Y26101D01*
X316395Y26221D01*
X316383Y26318D01*
X316359Y26414D01*
X316323Y26498D01*
X316299Y26570D01*
X316275Y26618D01*
X316262Y26655D01*
X316250Y26667D01*
X316178Y26763D01*
X316106Y26835D01*
X316022Y26907D01*
X315949Y26968D01*
X315877Y27004D01*
X315817Y27040D01*
X315781Y27064D01*
X315769D01*
X315636Y27112D01*
X315468Y27160D01*
X315299Y27196D01*
X315119Y27232D01*
X314962Y27269D01*
X314830Y27281D01*
X314782Y27293D01*
X314745Y27305D01*
X314709D01*
X314468Y27341D01*
X314252Y27377D01*
X314035Y27413D01*
X313843Y27449D01*
X313674Y27485D01*
X313505Y27534D01*
X313361Y27570D01*
X313228Y27606D01*
X313108Y27630D01*
X313012Y27666D01*
X312927Y27690D01*
X312855Y27714D01*
X312807Y27738D01*
X312771Y27750D01*
X312747Y27762D01*
D02*
G37*
G36*
X303850Y30459D02*
X303765D01*
X303597Y30447D01*
X303440Y30435D01*
X303284Y30399D01*
X303151Y30351D01*
X302886Y30242D01*
X302670Y30110D01*
X302501Y29978D01*
X302429Y29917D01*
X302381Y29869D01*
X302333Y29821D01*
X302297Y29797D01*
X302285Y29773D01*
X302272Y29761D01*
X302140Y29580D01*
X302044Y29364D01*
X301959Y29147D01*
X301899Y28930D01*
X301863Y28737D01*
X301851Y28653D01*
X301839Y28581D01*
X301827Y28521D01*
X301815Y28473D01*
Y28449D01*
Y28437D01*
X305776D01*
X305728Y28761D01*
X305655Y29051D01*
X305559Y29303D01*
X305451Y29520D01*
X305343Y29676D01*
X305246Y29809D01*
X305210Y29845D01*
X305186Y29881D01*
X305162Y29893D01*
Y29905D01*
X305054Y30002D01*
X304933Y30086D01*
X304704Y30230D01*
X304476Y30327D01*
X304247Y30387D01*
X304054Y30435D01*
X303970Y30447D01*
X303898D01*
X303850Y30459D01*
D02*
G37*
G36*
X392606Y32963D02*
X392509Y32638D01*
X392389Y32301D01*
X392281Y31952D01*
X392160Y31639D01*
X392112Y31483D01*
X392052Y31350D01*
X392016Y31230D01*
X391967Y31121D01*
X391943Y31037D01*
X391919Y30977D01*
X391895Y30929D01*
Y30917D01*
X390884Y28208D01*
X394219D01*
X393147Y31073D01*
X393027Y31422D01*
X392919Y31759D01*
X392822Y32085D01*
X392750Y32361D01*
X392714Y32494D01*
X392690Y32614D01*
X392666Y32710D01*
X392642Y32795D01*
X392630Y32867D01*
X392618Y32915D01*
X392606Y32951D01*
Y32963D01*
D02*
G37*
G36*
X335538Y32819D02*
X332745D01*
X332612Y32807D01*
X332492D01*
X332275Y32795D01*
X332119Y32771D01*
X331986Y32759D01*
X331902Y32735D01*
X331854Y32723D01*
X331842D01*
X331661Y32662D01*
X331505Y32578D01*
X331360Y32482D01*
X331240Y32385D01*
X331143Y32289D01*
X331083Y32217D01*
X331035Y32169D01*
X331023Y32145D01*
X330915Y31976D01*
X330842Y31795D01*
X330782Y31627D01*
X330746Y31458D01*
X330722Y31314D01*
X330710Y31206D01*
Y31157D01*
Y31121D01*
Y31109D01*
Y31097D01*
Y30941D01*
X330734Y30796D01*
X330794Y30531D01*
X330878Y30315D01*
X330975Y30122D01*
X331071Y29978D01*
X331155Y29869D01*
X331216Y29809D01*
X331228Y29785D01*
X331240D01*
X331348Y29701D01*
X331469Y29628D01*
X331745Y29520D01*
X332034Y29436D01*
X332323Y29388D01*
X332600Y29351D01*
X332721Y29339D01*
X332817D01*
X332901Y29327D01*
X335538D01*
Y32819D01*
D02*
G37*
G36*
X353344Y30459D02*
X353272D01*
X353116Y30447D01*
X352983Y30435D01*
X352839Y30399D01*
X352706Y30351D01*
X352478Y30242D01*
X352273Y30122D01*
X352104Y29990D01*
X351984Y29881D01*
X351948Y29833D01*
X351912Y29797D01*
X351900Y29785D01*
X351888Y29773D01*
X351791Y29640D01*
X351695Y29484D01*
X351562Y29159D01*
X351454Y28798D01*
X351394Y28461D01*
X351370Y28292D01*
X351346Y28135D01*
X351334Y28003D01*
Y27883D01*
X351322Y27786D01*
Y27702D01*
Y27654D01*
Y27642D01*
Y27401D01*
X351346Y27172D01*
X351370Y26968D01*
X351406Y26775D01*
X351454Y26594D01*
X351502Y26438D01*
X351550Y26293D01*
X351599Y26161D01*
X351647Y26053D01*
X351695Y25956D01*
X351743Y25872D01*
X351791Y25800D01*
X351827Y25752D01*
X351852Y25715D01*
X351864Y25691D01*
X351876Y25679D01*
X351984Y25571D01*
X352092Y25475D01*
X352201Y25378D01*
X352321Y25306D01*
X352550Y25198D01*
X352755Y25126D01*
X352947Y25077D01*
X353019Y25065D01*
X353092Y25053D01*
X353152Y25041D01*
X353224D01*
X353368Y25053D01*
X353501Y25065D01*
X353766Y25150D01*
X353994Y25246D01*
X354199Y25378D01*
X354356Y25499D01*
X354476Y25595D01*
X354524Y25643D01*
X354560Y25679D01*
X354572Y25691D01*
X354585Y25703D01*
X354681Y25836D01*
X354765Y25980D01*
X354910Y26305D01*
X355006Y26643D01*
X355078Y26980D01*
X355102Y27124D01*
X355114Y27269D01*
X355138Y27401D01*
Y27522D01*
X355150Y27606D01*
Y27678D01*
Y27726D01*
Y27738D01*
X355138Y27991D01*
X355126Y28232D01*
X355102Y28449D01*
X355066Y28653D01*
X355030Y28846D01*
X354982Y29014D01*
X354934Y29159D01*
X354885Y29291D01*
X354837Y29412D01*
X354789Y29520D01*
X354741Y29604D01*
X354705Y29676D01*
X354669Y29725D01*
X354645Y29761D01*
X354621Y29785D01*
Y29797D01*
X354512Y29917D01*
X354404Y30014D01*
X354296Y30110D01*
X354175Y30182D01*
X353958Y30303D01*
X353742Y30375D01*
X353561Y30423D01*
X353477Y30435D01*
X353405Y30447D01*
X353344Y30459D01*
D02*
G37*
G36*
X345567D02*
X345482D01*
X345326Y30447D01*
X345169Y30435D01*
X345025Y30399D01*
X344881Y30351D01*
X344628Y30242D01*
X344411Y30122D01*
X344243Y29990D01*
X344170Y29929D01*
X344110Y29881D01*
X344062Y29833D01*
X344026Y29797D01*
X344014Y29785D01*
X344002Y29773D01*
X343893Y29640D01*
X343797Y29496D01*
X343725Y29339D01*
X343652Y29183D01*
X343544Y28846D01*
X343472Y28533D01*
X343448Y28376D01*
X343436Y28232D01*
X343412Y28111D01*
Y28003D01*
X343400Y27907D01*
Y27847D01*
Y27798D01*
Y27786D01*
X343412Y27534D01*
X343424Y27293D01*
X343460Y27076D01*
X343496Y26871D01*
X343544Y26691D01*
X343592Y26522D01*
X343641Y26366D01*
X343701Y26233D01*
X343761Y26113D01*
X343809Y26005D01*
X343857Y25920D01*
X343905Y25848D01*
X343941Y25788D01*
X343978Y25752D01*
X343990Y25728D01*
X344002Y25715D01*
X344110Y25595D01*
X344230Y25499D01*
X344363Y25403D01*
X344483Y25330D01*
X344724Y25210D01*
X344965Y25126D01*
X345169Y25077D01*
X345254Y25065D01*
X345338Y25053D01*
X345398Y25041D01*
X345482D01*
X345651Y25053D01*
X345808Y25065D01*
X346097Y25150D01*
X346349Y25258D01*
X346566Y25378D01*
X346747Y25499D01*
X346807Y25559D01*
X346867Y25607D01*
X346915Y25655D01*
X346951Y25691D01*
X346963Y25703D01*
X346976Y25715D01*
X347084Y25848D01*
X347168Y25992D01*
X347252Y26149D01*
X347313Y26318D01*
X347421Y26655D01*
X347493Y26992D01*
X347517Y27136D01*
X347529Y27281D01*
X347541Y27413D01*
X347553Y27534D01*
X347565Y27618D01*
Y27690D01*
Y27738D01*
Y27750D01*
X347553Y28003D01*
X347541Y28232D01*
X347505Y28449D01*
X347469Y28641D01*
X347433Y28822D01*
X347373Y28990D01*
X347325Y29147D01*
X347264Y29279D01*
X347216Y29400D01*
X347156Y29496D01*
X347108Y29592D01*
X347072Y29664D01*
X347024Y29713D01*
X347000Y29749D01*
X346987Y29773D01*
X346976Y29785D01*
X346867Y29905D01*
X346747Y30014D01*
X346614Y30098D01*
X346494Y30170D01*
X346241Y30291D01*
X346012Y30375D01*
X345796Y30423D01*
X345711Y30435D01*
X345627Y30447D01*
X345567Y30459D01*
D02*
G37*
G36*
X371500Y15720D02*
X371488D01*
X371500Y15275D01*
X371512Y14998D01*
X371524Y14757D01*
X371560Y14552D01*
X371596Y14384D01*
X371633Y14251D01*
X371657Y14155D01*
X371681Y14107D01*
X371693Y14083D01*
X371801Y13890D01*
X371922Y13734D01*
X372054Y13589D01*
X372186Y13469D01*
X372307Y13372D01*
X372403Y13312D01*
X372475Y13264D01*
X372487Y13252D01*
X372499D01*
X372704Y13156D01*
X372921Y13084D01*
X373125Y13023D01*
X373318Y12987D01*
X373487Y12963D01*
X373607Y12951D01*
X373727D01*
X373980Y12963D01*
X374197Y12999D01*
X374378Y13047D01*
X374534Y13108D01*
X374642Y13168D01*
X374727Y13216D01*
X374787Y13252D01*
X374799Y13264D01*
X374919Y13397D01*
X375004Y13529D01*
X375076Y13662D01*
X375112Y13782D01*
X375136Y13890D01*
X375148Y13987D01*
X375160Y14035D01*
Y14059D01*
X375148Y14179D01*
X375136Y14275D01*
X375112Y14372D01*
X375076Y14456D01*
X375052Y14528D01*
X375028Y14576D01*
X375016Y14613D01*
X375004Y14625D01*
X374931Y14721D01*
X374859Y14793D01*
X374775Y14865D01*
X374703Y14926D01*
X374630Y14962D01*
X374570Y14998D01*
X374534Y15022D01*
X374522D01*
X374390Y15070D01*
X374221Y15118D01*
X374053Y15154D01*
X373872Y15191D01*
X373715Y15227D01*
X373583Y15239D01*
X373535Y15251D01*
X373499Y15263D01*
X373463D01*
X373222Y15299D01*
X373005Y15335D01*
X372788Y15371D01*
X372596Y15407D01*
X372427Y15443D01*
X372259Y15491D01*
X372114Y15528D01*
X371982Y15564D01*
X371861Y15588D01*
X371765Y15624D01*
X371681Y15648D01*
X371609Y15672D01*
X371560Y15696D01*
X371524Y15708D01*
X371500Y15720D01*
D02*
G37*
G36*
X329049D02*
X329036D01*
X329049Y15275D01*
X329061Y14998D01*
X329073Y14757D01*
X329109Y14552D01*
X329145Y14384D01*
X329181Y14251D01*
X329205Y14155D01*
X329229Y14107D01*
X329241Y14083D01*
X329350Y13890D01*
X329470Y13734D01*
X329602Y13589D01*
X329735Y13469D01*
X329855Y13372D01*
X329952Y13312D01*
X330024Y13264D01*
X330036Y13252D01*
X330048D01*
X330252Y13156D01*
X330469Y13084D01*
X330674Y13023D01*
X330867Y12987D01*
X331035Y12963D01*
X331155Y12951D01*
X331276D01*
X331529Y12963D01*
X331745Y12999D01*
X331926Y13047D01*
X332082Y13108D01*
X332191Y13168D01*
X332275Y13216D01*
X332335Y13252D01*
X332347Y13264D01*
X332468Y13397D01*
X332552Y13529D01*
X332624Y13662D01*
X332660Y13782D01*
X332685Y13890D01*
X332696Y13987D01*
X332709Y14035D01*
Y14059D01*
X332696Y14179D01*
X332685Y14275D01*
X332660Y14372D01*
X332624Y14456D01*
X332600Y14528D01*
X332576Y14576D01*
X332564Y14613D01*
X332552Y14625D01*
X332480Y14721D01*
X332407Y14793D01*
X332323Y14865D01*
X332251Y14926D01*
X332179Y14962D01*
X332119Y14998D01*
X332082Y15022D01*
X332070D01*
X331938Y15070D01*
X331769Y15118D01*
X331601Y15154D01*
X331420Y15191D01*
X331264Y15227D01*
X331131Y15239D01*
X331083Y15251D01*
X331047Y15263D01*
X331011D01*
X330770Y15299D01*
X330553Y15335D01*
X330337Y15371D01*
X330144Y15407D01*
X329976Y15443D01*
X329807Y15491D01*
X329663Y15528D01*
X329530Y15564D01*
X329410Y15588D01*
X329313Y15624D01*
X329229Y15648D01*
X329157Y15672D01*
X329109Y15696D01*
X329073Y15708D01*
X329049Y15720D01*
D02*
G37*
G36*
X311820Y18417D02*
X311735D01*
X311567Y18405D01*
X311411Y18393D01*
X311254Y18357D01*
X311122Y18309D01*
X310857Y18200D01*
X310640Y18068D01*
X310471Y17936D01*
X310399Y17875D01*
X310351Y17827D01*
X310303Y17779D01*
X310267Y17755D01*
X310255Y17731D01*
X310243Y17719D01*
X310110Y17538D01*
X310014Y17321D01*
X309930Y17105D01*
X309869Y16888D01*
X309833Y16695D01*
X309821Y16611D01*
X309809Y16539D01*
X309797Y16479D01*
X309785Y16431D01*
Y16407D01*
Y16394D01*
X313746D01*
X313698Y16719D01*
X313626Y17009D01*
X313529Y17261D01*
X313421Y17478D01*
X313313Y17635D01*
X313216Y17767D01*
X313180Y17803D01*
X313156Y17839D01*
X313132Y17851D01*
Y17863D01*
X313024Y17960D01*
X312903Y18044D01*
X312675Y18188D01*
X312446Y18285D01*
X312217Y18345D01*
X312024Y18393D01*
X311940Y18405D01*
X311868D01*
X311820Y18417D01*
D02*
G37*
%LPD*%
M02*
